(kicad_sch
	(version 20250114)
	(generator "eeschema")
	(generator_version "9.0")
	(paper "A4")
	(title_block
		(title " M.2 to OCuLink adapter")
		(date "2025-08-14")
		(rev "1.0.2")
		(company "Antmicro Ltd")
		(comment 1 "www.antmicro.com")
	)
	(text "REF Clock config"
		(exclude_from_sim no)
		(at 234.442 21.082 0)
		(effects
			(font
				(size 1.27 1.27)
			)
		)
	)
	(text "Endpoint\n"
		(exclude_from_sim no)
		(at 219.71 32.258 0)
		(effects
			(font
				(size 1.27 1.27)
			)
		)
	)
	(text "x"
		(exclude_from_sim no)
		(at 246.888 32.512 0)
		(effects
			(font
				(size 2.54 2.54)
			)
		)
	)
	(text "R6\n"
		(exclude_from_sim no)
		(at 227.838 25.146 0)
		(effects
			(font
				(size 1.27 1.27)
			)
		)
	)
	(text "Root"
		(exclude_from_sim no)
		(at 219.71 28.702 0)
		(effects
			(font
				(size 1.27 1.27)
			)
		)
	)
	(text "x"
		(exclude_from_sim no)
		(at 240.538 28.448 0)
		(effects
			(font
				(size 2.54 2.54)
			)
		)
	)
	(text "x"
		(exclude_from_sim no)
		(at 259.588 28.448 0)
		(effects
			(font
				(size 2.54 2.54)
			)
		)
	)
	(text "Used as test pads"
		(exclude_from_sim no)
		(at 249.428 49.784 0)
		(effects
			(font
				(size 1.27 1.27)
			)
		)
	)
	(text "x"
		(exclude_from_sim no)
		(at 234.188 32.512 0)
		(effects
			(font
				(size 2.54 2.54)
			)
		)
	)
	(text "x"
		(exclude_from_sim no)
		(at 227.838 28.448 0)
		(effects
			(font
				(size 2.54 2.54)
			)
		)
	)
	(text "R3"
		(exclude_from_sim no)
		(at 247.142 25.146 0)
		(effects
			(font
				(size 1.27 1.27)
			)
		)
	)
	(text "x"
		(exclude_from_sim no)
		(at 266.192 28.448 0)
		(effects
			(font
				(size 2.54 2.54)
			)
		)
	)
	(text "R4"
		(exclude_from_sim no)
		(at 240.538 25.146 0)
		(effects
			(font
				(size 1.27 1.27)
			)
		)
	)
	(text "R13\n"
		(exclude_from_sim no)
		(at 265.938 25.146 0)
		(effects
			(font
				(size 1.27 1.27)
			)
		)
	)
	(text "x"
		(exclude_from_sim no)
		(at 253.238 32.512 0)
		(effects
			(font
				(size 2.54 2.54)
			)
		)
	)
	(text "R5"
		(exclude_from_sim no)
		(at 234.188 25.146 0)
		(effects
			(font
				(size 1.27 1.27)
			)
		)
	)
	(text "R2"
		(exclude_from_sim no)
		(at 253.238 25.146 0)
		(effects
			(font
				(size 1.27 1.27)
			)
		)
	)
	(text "R10\n"
		(exclude_from_sim no)
		(at 259.588 25.146 0)
		(effects
			(font
				(size 1.27 1.27)
			)
		)
	)
	(junction
		(at 181.61 34.29)
		(diameter 0)
		(color 0 0 0 0)
	)
	(junction
		(at 179.07 43.18)
		(diameter 0)
		(color 0 0 0 0)
	)
	(junction
		(at 240.03 59.69)
		(diameter 0)
		(color 0 0 0 0)
	)
	(junction
		(at 113.03 67.31)
		(diameter 0)
		(color 0 0 0 0)
	)
	(junction
		(at 191.77 60.96)
		(diameter 0)
		(color 0 0 0 0)
	)
	(junction
		(at 121.92 60.96)
		(diameter 0)
		(color 0 0 0 0)
	)
	(junction
		(at 36.83 95.25)
		(diameter 0)
		(color 0 0 0 0)
	)
	(junction
		(at 113.03 60.96)
		(diameter 0)
		(color 0 0 0 0)
	)
	(junction
		(at 218.44 72.39)
		(diameter 0)
		(color 0 0 0 0)
	)
	(junction
		(at 172.72 90.17)
		(diameter 0)
		(color 0 0 0 0)
	)
	(junction
		(at 139.7 60.96)
		(diameter 0)
		(color 0 0 0 0)
	)
	(junction
		(at 218.44 60.96)
		(diameter 0)
		(color 0 0 0 0)
	)
	(junction
		(at 44.45 100.33)
		(diameter 0)
		(color 0 0 0 0)
	)
	(junction
		(at 227.33 64.77)
		(diameter 0)
		(color 0 0 0 0)
	)
	(junction
		(at 179.07 34.29)
		(diameter 0)
		(color 0 0 0 0)
	)
	(junction
		(at 274.32 151.13)
		(diameter 0)
		(color 0 0 0 0)
	)
	(no_connect
		(at 52.07 90.17)
	)
	(no_connect
		(at 246.38 69.85)
	)
	(no_connect
		(at 52.07 92.71)
	)
	(no_connect
		(at 90.17 151.13)
	)
	(no_connect
		(at 52.07 102.87)
	)
	(bus_entry
		(at 146.05 31.75)
		(size -1.27 -1.27)
		(stroke
			(width 0)
			(type default)
		)
	)
	(bus_entry
		(at 116.84 144.78)
		(size -2.54 2.54)
		(stroke
			(width 0)
			(type default)
		)
	)
	(bus_entry
		(at 181.61 93.98)
		(size 1.27 1.27)
		(stroke
			(width 0)
			(type default)
		)
	)
	(bus_entry
		(at 114.3 132.08)
		(size 2.54 -2.54)
		(stroke
			(width 0)
			(type default)
		)
	)
	(bus_entry
		(at 114.3 128.27)
		(size 2.54 -2.54)
		(stroke
			(width 0)
			(type default)
		)
	)
	(bus_entry
		(at 114.3 96.52)
		(size 2.54 -2.54)
		(stroke
			(width 0)
			(type default)
		)
	)
	(bus_entry
		(at 116.84 142.24)
		(size -2.54 2.54)
		(stroke
			(width 0)
			(type default)
		)
	)
	(bus_entry
		(at 181.61 132.08)
		(size 1.27 1.27)
		(stroke
			(width 0)
			(type default)
		)
	)
	(bus_entry
		(at 181.61 119.38)
		(size 1.27 1.27)
		(stroke
			(width 0)
			(type default)
		)
	)
	(bus_entry
		(at 114.3 125.73)
		(size 2.54 -2.54)
		(stroke
			(width 0)
			(type default)
		)
	)
	(bus_entry
		(at 114.3 140.97)
		(size 2.54 -2.54)
		(stroke
			(width 0)
			(type default)
		)
	)
	(bus_entry
		(at 114.3 100.33)
		(size 2.54 -2.54)
		(stroke
			(width 0)
			(type default)
		)
	)
	(bus_entry
		(at 181.61 134.62)
		(size 1.27 1.27)
		(stroke
			(width 0)
			(type default)
		)
	)
	(bus_entry
		(at 114.3 119.38)
		(size 2.54 -2.54)
		(stroke
			(width 0)
			(type default)
		)
	)
	(bus_entry
		(at 114.3 121.92)
		(size 2.54 -2.54)
		(stroke
			(width 0)
			(type default)
		)
	)
	(bus_entry
		(at 181.61 127)
		(size 1.27 1.27)
		(stroke
			(width 0)
			(type default)
		)
	)
	(bus_entry
		(at 181.61 109.22)
		(size 1.27 1.27)
		(stroke
			(width 0)
			(type default)
		)
	)
	(bus_entry
		(at 181.61 142.24)
		(size 1.27 1.27)
		(stroke
			(width 0)
			(type default)
		)
	)
	(bus_entry
		(at 114.3 102.87)
		(size 2.54 -2.54)
		(stroke
			(width 0)
			(type default)
		)
	)
	(bus_entry
		(at 114.3 106.68)
		(size 2.54 -2.54)
		(stroke
			(width 0)
			(type default)
		)
	)
	(bus_entry
		(at 146.05 34.29)
		(size -1.27 -1.27)
		(stroke
			(width 0)
			(type default)
		)
	)
	(bus_entry
		(at 114.3 109.22)
		(size 2.54 -2.54)
		(stroke
			(width 0)
			(type default)
		)
	)
	(bus_entry
		(at 181.61 124.46)
		(size 1.27 1.27)
		(stroke
			(width 0)
			(type default)
		)
	)
	(bus_entry
		(at 181.61 149.86)
		(size 1.27 1.27)
		(stroke
			(width 0)
			(type default)
		)
	)
	(bus_entry
		(at 181.61 111.76)
		(size 1.27 1.27)
		(stroke
			(width 0)
			(type default)
		)
	)
	(bus_entry
		(at 181.61 101.6)
		(size 1.27 1.27)
		(stroke
			(width 0)
			(type default)
		)
	)
	(bus_entry
		(at 181.61 96.52)
		(size 1.27 1.27)
		(stroke
			(width 0)
			(type default)
		)
	)
	(bus_entry
		(at 114.3 93.98)
		(size 2.54 -2.54)
		(stroke
			(width 0)
			(type default)
		)
	)
	(bus_entry
		(at 181.61 139.7)
		(size 1.27 1.27)
		(stroke
			(width 0)
			(type default)
		)
	)
	(bus_entry
		(at 181.61 104.14)
		(size 1.27 1.27)
		(stroke
			(width 0)
			(type default)
		)
	)
	(bus_entry
		(at 114.3 138.43)
		(size 2.54 -2.54)
		(stroke
			(width 0)
			(type default)
		)
	)
	(bus_entry
		(at 114.3 113.03)
		(size 2.54 -2.54)
		(stroke
			(width 0)
			(type default)
		)
	)
	(bus_entry
		(at 181.61 147.32)
		(size 1.27 1.27)
		(stroke
			(width 0)
			(type default)
		)
	)
	(bus_entry
		(at 114.3 115.57)
		(size 2.54 -2.54)
		(stroke
			(width 0)
			(type default)
		)
	)
	(bus_entry
		(at 114.3 134.62)
		(size 2.54 -2.54)
		(stroke
			(width 0)
			(type default)
		)
	)
	(bus_entry
		(at 181.61 116.84)
		(size 1.27 1.27)
		(stroke
			(width 0)
			(type default)
		)
	)
	(bus
		(pts
			(xy 116.84 119.38) (xy 116.84 123.19)
		)
		(stroke
			(width 0)
			(type default)
		)
	)
	(wire
		(pts
			(xy 274.32 148.59) (xy 274.32 151.13)
		)
		(stroke
			(width 0)
			(type default)
		)
	)
	(wire
		(pts
			(xy 33.02 95.25) (xy 36.83 95.25)
		)
		(stroke
			(width 0)
			(type default)
		)
	)
	(wire
		(pts
			(xy 218.44 72.39) (xy 218.44 71.12)
		)
		(stroke
			(width 0)
			(type default)
		)
	)
	(bus
		(pts
			(xy 181.61 93.98) (xy 181.61 96.52)
		)
		(stroke
			(width 0)
			(type default)
		)
	)
	(bus
		(pts
			(xy 181.61 119.38) (xy 181.61 124.46)
		)
		(stroke
			(width 0)
			(type default)
		)
	)
	(bus
		(pts
			(xy 144.78 29.21) (xy 144.78 30.48)
		)
		(stroke
			(width 0)
			(type default)
		)
	)
	(wire
		(pts
			(xy 182.88 133.35) (xy 246.38 133.35)
		)
		(stroke
			(width 0)
			(type default)
		)
	)
	(wire
		(pts
			(xy 179.07 43.18) (xy 179.07 40.64)
		)
		(stroke
			(width 0)
			(type default)
		)
	)
	(bus
		(pts
			(xy 181.61 132.08) (xy 181.61 134.62)
		)
		(stroke
			(width 0)
			(type default)
		)
	)
	(bus
		(pts
			(xy 181.61 142.24) (xy 181.61 147.32)
		)
		(stroke
			(width 0)
			(type default)
		)
	)
	(wire
		(pts
			(xy 90.17 119.38) (xy 114.3 119.38)
		)
		(stroke
			(width 0)
			(type default)
		)
	)
	(bus
		(pts
			(xy 144.78 30.48) (xy 144.78 33.02)
		)
		(stroke
			(width 0)
			(type default)
		)
	)
	(bus
		(pts
			(xy 172.72 90.17) (xy 180.34 90.17)
		)
		(stroke
			(width 0)
			(type default)
		)
	)
	(wire
		(pts
			(xy 90.17 125.73) (xy 114.3 125.73)
		)
		(stroke
			(width 0)
			(type default)
		)
	)
	(wire
		(pts
			(xy 90.17 102.87) (xy 114.3 102.87)
		)
		(stroke
			(width 0)
			(type default)
		)
	)
	(bus
		(pts
			(xy 116.84 100.33) (xy 116.84 104.14)
		)
		(stroke
			(width 0)
			(type default)
		)
	)
	(wire
		(pts
			(xy 160.02 64.77) (xy 227.33 64.77)
		)
		(stroke
			(width 0)
			(type default)
		)
	)
	(wire
		(pts
			(xy 226.06 90.17) (xy 220.98 90.17)
		)
		(stroke
			(width 0)
			(type default)
		)
	)
	(wire
		(pts
			(xy 240.03 59.69) (xy 246.38 59.69)
		)
		(stroke
			(width 0)
			(type default)
		)
	)
	(polyline
		(pts
			(xy 214.63 30.48) (xy 222.25 30.48)
		)
		(stroke
			(width 0)
			(type default)
		)
	)
	(bus
		(pts
			(xy 116.84 110.49) (xy 116.84 113.03)
		)
		(stroke
			(width 0)
			(type default)
		)
	)
	(wire
		(pts
			(xy 227.33 72.39) (xy 218.44 72.39)
		)
		(stroke
			(width 0)
			(type default)
		)
	)
	(wire
		(pts
			(xy 214.63 87.63) (xy 246.38 87.63)
		)
		(stroke
			(width 0)
			(type default)
		)
	)
	(wire
		(pts
			(xy 182.88 135.89) (xy 246.38 135.89)
		)
		(stroke
			(width 0)
			(type default)
		)
	)
	(wire
		(pts
			(xy 181.61 34.29) (xy 190.5 34.29)
		)
		(stroke
			(width 0)
			(type default)
		)
	)
	(wire
		(pts
			(xy 50.8 151.13) (xy 52.07 151.13)
		)
		(stroke
			(width 0)
			(type default)
		)
	)
	(bus
		(pts
			(xy 181.61 134.62) (xy 181.61 139.7)
		)
		(stroke
			(width 0)
			(type default)
		)
	)
	(wire
		(pts
			(xy 90.17 144.78) (xy 114.3 144.78)
		)
		(stroke
			(width 0)
			(type default)
		)
	)
	(wire
		(pts
			(xy 154.94 19.05) (xy 154.94 31.75)
		)
		(stroke
			(width 0)
			(type default)
		)
	)
	(bus
		(pts
			(xy 116.84 116.84) (xy 116.84 119.38)
		)
		(stroke
			(width 0)
			(type default)
		)
	)
	(wire
		(pts
			(xy 204.47 22.86) (xy 204.47 26.67)
		)
		(stroke
			(width 0)
			(type default)
		)
	)
	(wire
		(pts
			(xy 204.47 87.63) (xy 209.55 87.63)
		)
		(stroke
			(width 0)
			(type default)
		)
	)
	(wire
		(pts
			(xy 227.33 64.77) (xy 246.38 64.77)
		)
		(stroke
			(width 0)
			(type default)
		)
	)
	(polyline
		(pts
			(xy 231.14 22.86) (xy 231.14 34.29)
		)
		(stroke
			(width 0)
			(type default)
		)
	)
	(wire
		(pts
			(xy 181.61 34.29) (xy 181.61 35.56)
		)
		(stroke
			(width 0)
			(type default)
		)
	)
	(wire
		(pts
			(xy 90.17 138.43) (xy 114.3 138.43)
		)
		(stroke
			(width 0)
			(type default)
		)
	)
	(bus
		(pts
			(xy 116.84 135.89) (xy 116.84 138.43)
		)
		(stroke
			(width 0)
			(type default)
		)
	)
	(wire
		(pts
			(xy 104.14 63.5) (xy 106.68 60.96)
		)
		(stroke
			(width 0)
			(type default)
		)
	)
	(wire
		(pts
			(xy 160.02 60.96) (xy 191.77 60.96)
		)
		(stroke
			(width 0)
			(type default)
		)
	)
	(wire
		(pts
			(xy 190.5 19.05) (xy 154.94 19.05)
		)
		(stroke
			(width 0)
			(type default)
		)
	)
	(wire
		(pts
			(xy 182.88 148.59) (xy 246.38 148.59)
		)
		(stroke
			(width 0)
			(type default)
		)
	)
	(wire
		(pts
			(xy 218.44 60.96) (xy 218.44 66.04)
		)
		(stroke
			(width 0)
			(type default)
		)
	)
	(wire
		(pts
			(xy 243.84 80.01) (xy 246.38 80.01)
		)
		(stroke
			(width 0)
			(type default)
		)
	)
	(wire
		(pts
			(xy 246.38 105.41) (xy 182.88 105.41)
		)
		(stroke
			(width 0)
			(type default)
		)
	)
	(bus
		(pts
			(xy 116.84 91.44) (xy 116.84 93.98)
		)
		(stroke
			(width 0)
			(type default)
		)
	)
	(wire
		(pts
			(xy 182.88 125.73) (xy 246.38 125.73)
		)
		(stroke
			(width 0)
			(type default)
		)
	)
	(wire
		(pts
			(xy 204.47 86.36) (xy 204.47 87.63)
		)
		(stroke
			(width 0)
			(type default)
		)
	)
	(wire
		(pts
			(xy 204.47 31.75) (xy 204.47 34.29)
		)
		(stroke
			(width 0)
			(type default)
		)
	)
	(bus
		(pts
			(xy 181.61 101.6) (xy 181.61 104.14)
		)
		(stroke
			(width 0)
			(type default)
		)
	)
	(wire
		(pts
			(xy 33.02 100.33) (xy 44.45 100.33)
		)
		(stroke
			(width 0)
			(type default)
		)
	)
	(bus
		(pts
			(xy 116.84 132.08) (xy 116.84 135.89)
		)
		(stroke
			(width 0)
			(type default)
		)
	)
	(bus
		(pts
			(xy 116.84 113.03) (xy 116.84 116.84)
		)
		(stroke
			(width 0)
			(type default)
		)
	)
	(wire
		(pts
			(xy 154.94 64.77) (xy 139.7 64.77)
		)
		(stroke
			(width 0)
			(type default)
		)
	)
	(bus
		(pts
			(xy 116.84 106.68) (xy 116.84 110.49)
		)
		(stroke
			(width 0)
			(type default)
		)
	)
	(bus
		(pts
			(xy 181.61 91.44) (xy 181.61 93.98)
		)
		(stroke
			(width 0)
			(type default)
		)
	)
	(wire
		(pts
			(xy 90.17 128.27) (xy 114.3 128.27)
		)
		(stroke
			(width 0)
			(type default)
		)
	)
	(wire
		(pts
			(xy 271.78 148.59) (xy 274.32 148.59)
		)
		(stroke
			(width 0)
			(type default)
		)
	)
	(polyline
		(pts
			(xy 218.44 26.67) (xy 269.24 26.67)
		)
		(stroke
			(width 0)
			(type default)
		)
	)
	(bus
		(pts
			(xy 116.84 129.54) (xy 116.84 132.08)
		)
		(stroke
			(width 0)
			(type default)
		)
	)
	(wire
		(pts
			(xy 238.76 62.23) (xy 246.38 62.23)
		)
		(stroke
			(width 0)
			(type default)
		)
	)
	(wire
		(pts
			(xy 246.38 120.65) (xy 182.88 120.65)
		)
		(stroke
			(width 0)
			(type default)
		)
	)
	(wire
		(pts
			(xy 240.03 50.8) (xy 240.03 52.07)
		)
		(stroke
			(width 0)
			(type default)
		)
	)
	(wire
		(pts
			(xy 226.06 85.09) (xy 220.98 85.09)
		)
		(stroke
			(width 0)
			(type default)
		)
	)
	(wire
		(pts
			(xy 113.03 60.96) (xy 121.92 60.96)
		)
		(stroke
			(width 0)
			(type default)
		)
	)
	(bus
		(pts
			(xy 181.61 139.7) (xy 181.61 142.24)
		)
		(stroke
			(width 0)
			(type default)
		)
	)
	(wire
		(pts
			(xy 231.14 90.17) (xy 246.38 90.17)
		)
		(stroke
			(width 0)
			(type default)
		)
	)
	(wire
		(pts
			(xy 104.14 63.5) (xy 104.14 88.9)
		)
		(stroke
			(width 0)
			(type default)
		)
	)
	(wire
		(pts
			(xy 243.84 77.47) (xy 246.38 77.47)
		)
		(stroke
			(width 0)
			(type default)
		)
	)
	(wire
		(pts
			(xy 90.17 140.97) (xy 114.3 140.97)
		)
		(stroke
			(width 0)
			(type default)
		)
	)
	(wire
		(pts
			(xy 181.61 22.86) (xy 181.61 27.94)
		)
		(stroke
			(width 0)
			(type default)
		)
	)
	(wire
		(pts
			(xy 44.45 100.33) (xy 52.07 100.33)
		)
		(stroke
			(width 0)
			(type default)
		)
	)
	(wire
		(pts
			(xy 50.8 151.13) (xy 50.8 152.4)
		)
		(stroke
			(width 0)
			(type default)
		)
	)
	(bus
		(pts
			(xy 116.84 93.98) (xy 116.84 97.79)
		)
		(stroke
			(width 0)
			(type default)
		)
	)
	(bus
		(pts
			(xy 118.11 139.7) (xy 116.84 140.97)
		)
		(stroke
			(width 0)
			(type default)
		)
	)
	(wire
		(pts
			(xy 203.2 22.86) (xy 204.47 22.86)
		)
		(stroke
			(width 0)
			(type default)
		)
	)
	(wire
		(pts
			(xy 246.38 85.09) (xy 231.14 85.09)
		)
		(stroke
			(width 0)
			(type default)
		)
	)
	(wire
		(pts
			(xy 274.32 151.13) (xy 274.32 153.67)
		)
		(stroke
			(width 0)
			(type default)
		)
	)
	(bus
		(pts
			(xy 116.84 104.14) (xy 116.84 106.68)
		)
		(stroke
			(width 0)
			(type default)
		)
	)
	(wire
		(pts
			(xy 182.88 151.13) (xy 246.38 151.13)
		)
		(stroke
			(width 0)
			(type default)
		)
	)
	(wire
		(pts
			(xy 168.91 43.18) (xy 170.18 43.18)
		)
		(stroke
			(width 0)
			(type default)
		)
	)
	(wire
		(pts
			(xy 234.95 59.69) (xy 240.03 59.69)
		)
		(stroke
			(width 0)
			(type default)
		)
	)
	(wire
		(pts
			(xy 113.03 67.31) (xy 121.92 67.31)
		)
		(stroke
			(width 0)
			(type default)
		)
	)
	(polyline
		(pts
			(xy 250.19 22.86) (xy 250.19 34.29)
		)
		(stroke
			(width 0)
			(type default)
		)
	)
	(wire
		(pts
			(xy 90.17 100.33) (xy 114.3 100.33)
		)
		(stroke
			(width 0)
			(type default)
		)
	)
	(polyline
		(pts
			(xy 243.84 22.86) (xy 243.84 34.29)
		)
		(stroke
			(width 0)
			(type default)
		)
	)
	(bus
		(pts
			(xy 144.78 33.02) (xy 144.78 34.29)
		)
		(stroke
			(width 0)
			(type default)
		)
	)
	(polyline
		(pts
			(xy 262.89 22.86) (xy 262.89 34.29)
		)
		(stroke
			(width 0)
			(type default)
		)
	)
	(wire
		(pts
			(xy 113.03 67.31) (xy 113.03 66.04)
		)
		(stroke
			(width 0)
			(type default)
		)
	)
	(wire
		(pts
			(xy 90.17 115.57) (xy 114.3 115.57)
		)
		(stroke
			(width 0)
			(type default)
		)
	)
	(bus
		(pts
			(xy 181.61 109.22) (xy 181.61 111.76)
		)
		(stroke
			(width 0)
			(type default)
		)
	)
	(wire
		(pts
			(xy 227.33 64.77) (xy 227.33 66.04)
		)
		(stroke
			(width 0)
			(type default)
		)
	)
	(polyline
		(pts
			(xy 256.54 22.86) (xy 256.54 34.29)
		)
		(stroke
			(width 0)
			(type default)
		)
	)
	(wire
		(pts
			(xy 246.38 113.03) (xy 182.88 113.03)
		)
		(stroke
			(width 0)
			(type default)
		)
	)
	(wire
		(pts
			(xy 121.92 60.96) (xy 139.7 60.96)
		)
		(stroke
			(width 0)
			(type default)
		)
	)
	(wire
		(pts
			(xy 179.07 46.99) (xy 179.07 43.18)
		)
		(stroke
			(width 0)
			(type default)
		)
	)
	(wire
		(pts
			(xy 90.17 134.62) (xy 114.3 134.62)
		)
		(stroke
			(width 0)
			(type default)
		)
	)
	(wire
		(pts
			(xy 246.38 118.11) (xy 182.88 118.11)
		)
		(stroke
			(width 0)
			(type default)
		)
	)
	(wire
		(pts
			(xy 36.83 95.25) (xy 52.07 95.25)
		)
		(stroke
			(width 0)
			(type default)
		)
	)
	(wire
		(pts
			(xy 90.17 147.32) (xy 114.3 147.32)
		)
		(stroke
			(width 0)
			(type default)
		)
	)
	(wire
		(pts
			(xy 179.07 33.02) (xy 179.07 34.29)
		)
		(stroke
			(width 0)
			(type default)
		)
	)
	(wire
		(pts
			(xy 179.07 25.4) (xy 179.07 27.94)
		)
		(stroke
			(width 0)
			(type default)
		)
	)
	(wire
		(pts
			(xy 90.17 113.03) (xy 114.3 113.03)
		)
		(stroke
			(width 0)
			(type default)
		)
	)
	(wire
		(pts
			(xy 139.7 60.96) (xy 154.94 60.96)
		)
		(stroke
			(width 0)
			(type default)
		)
	)
	(polyline
		(pts
			(xy 218.44 30.48) (xy 269.24 30.48)
		)
		(stroke
			(width 0)
			(type default)
		)
	)
	(wire
		(pts
			(xy 182.88 143.51) (xy 246.38 143.51)
		)
		(stroke
			(width 0)
			(type default)
		)
	)
	(bus
		(pts
			(xy 181.61 96.52) (xy 181.61 101.6)
		)
		(stroke
			(width 0)
			(type default)
		)
	)
	(wire
		(pts
			(xy 218.44 60.96) (xy 238.76 60.96)
		)
		(stroke
			(width 0)
			(type default)
		)
	)
	(wire
		(pts
			(xy 146.05 34.29) (xy 179.07 34.29)
		)
		(stroke
			(width 0)
			(type default)
		)
	)
	(wire
		(pts
			(xy 181.61 33.02) (xy 181.61 34.29)
		)
		(stroke
			(width 0)
			(type default)
		)
	)
	(bus
		(pts
			(xy 181.61 127) (xy 181.61 132.08)
		)
		(stroke
			(width 0)
			(type default)
		)
	)
	(wire
		(pts
			(xy 182.88 128.27) (xy 246.38 128.27)
		)
		(stroke
			(width 0)
			(type default)
		)
	)
	(wire
		(pts
			(xy 181.61 44.45) (xy 181.61 40.64)
		)
		(stroke
			(width 0)
			(type default)
		)
	)
	(bus
		(pts
			(xy 181.61 116.84) (xy 181.61 119.38)
		)
		(stroke
			(width 0)
			(type default)
		)
	)
	(wire
		(pts
			(xy 246.38 97.79) (xy 182.88 97.79)
		)
		(stroke
			(width 0)
			(type default)
		)
	)
	(bus
		(pts
			(xy 116.84 123.19) (xy 116.84 125.73)
		)
		(stroke
			(width 0)
			(type default)
		)
	)
	(wire
		(pts
			(xy 90.17 109.22) (xy 114.3 109.22)
		)
		(stroke
			(width 0)
			(type default)
		)
	)
	(wire
		(pts
			(xy 234.95 50.8) (xy 234.95 59.69)
		)
		(stroke
			(width 0)
			(type default)
		)
	)
	(wire
		(pts
			(xy 36.83 93.98) (xy 36.83 95.25)
		)
		(stroke
			(width 0)
			(type default)
		)
	)
	(wire
		(pts
			(xy 102.87 90.17) (xy 104.14 88.9)
		)
		(stroke
			(width 0)
			(type default)
		)
	)
	(wire
		(pts
			(xy 246.38 110.49) (xy 182.88 110.49)
		)
		(stroke
			(width 0)
			(type default)
		)
	)
	(wire
		(pts
			(xy 246.38 102.87) (xy 182.88 102.87)
		)
		(stroke
			(width 0)
			(type default)
		)
	)
	(wire
		(pts
			(xy 175.26 43.18) (xy 179.07 43.18)
		)
		(stroke
			(width 0)
			(type default)
		)
	)
	(wire
		(pts
			(xy 90.17 132.08) (xy 114.3 132.08)
		)
		(stroke
			(width 0)
			(type default)
		)
	)
	(bus
		(pts
			(xy 143.51 27.94) (xy 140.97 27.94)
		)
		(stroke
			(width 0)
			(type default)
		)
	)
	(wire
		(pts
			(xy 246.38 95.25) (xy 182.88 95.25)
		)
		(stroke
			(width 0)
			(type default)
		)
	)
	(bus
		(pts
			(xy 181.61 147.32) (xy 181.61 149.86)
		)
		(stroke
			(width 0)
			(type default)
		)
	)
	(wire
		(pts
			(xy 274.32 151.13) (xy 271.78 151.13)
		)
		(stroke
			(width 0)
			(type default)
		)
	)
	(wire
		(pts
			(xy 190.5 34.29) (xy 190.5 19.05)
		)
		(stroke
			(width 0)
			(type default)
		)
	)
	(wire
		(pts
			(xy 240.03 50.8) (xy 234.95 50.8)
		)
		(stroke
			(width 0)
			(type default)
		)
	)
	(wire
		(pts
			(xy 90.17 106.68) (xy 114.3 106.68)
		)
		(stroke
			(width 0)
			(type default)
		)
	)
	(wire
		(pts
			(xy 240.03 57.15) (xy 240.03 59.69)
		)
		(stroke
			(width 0)
			(type default)
		)
	)
	(bus
		(pts
			(xy 181.61 104.14) (xy 181.61 109.22)
		)
		(stroke
			(width 0)
			(type default)
		)
	)
	(wire
		(pts
			(xy 25.4 105.41) (xy 25.4 107.95)
		)
		(stroke
			(width 0)
			(type default)
		)
	)
	(bus
		(pts
			(xy 181.61 91.44) (xy 180.34 90.17)
		)
		(stroke
			(width 0)
			(type default)
		)
	)
	(polyline
		(pts
			(xy 218.44 26.67) (xy 214.63 26.67)
		)
		(stroke
			(width 0)
			(type default)
		)
	)
	(bus
		(pts
			(xy 181.61 124.46) (xy 181.61 127)
		)
		(stroke
			(width 0)
			(type default)
		)
	)
	(wire
		(pts
			(xy 139.7 64.77) (xy 139.7 60.96)
		)
		(stroke
			(width 0)
			(type default)
		)
	)
	(wire
		(pts
			(xy 238.76 60.96) (xy 238.76 62.23)
		)
		(stroke
			(width 0)
			(type default)
		)
	)
	(bus
		(pts
			(xy 118.11 90.17) (xy 116.84 91.44)
		)
		(stroke
			(width 0)
			(type default)
		)
	)
	(wire
		(pts
			(xy 227.33 72.39) (xy 227.33 71.12)
		)
		(stroke
			(width 0)
			(type default)
		)
	)
	(bus
		(pts
			(xy 172.72 83.82) (xy 172.72 90.17)
		)
		(stroke
			(width 0)
			(type default)
		)
	)
	(bus
		(pts
			(xy 181.61 111.76) (xy 181.61 116.84)
		)
		(stroke
			(width 0)
			(type default)
		)
	)
	(polyline
		(pts
			(xy 224.79 22.86) (xy 224.79 34.29)
		)
		(stroke
			(width 0)
			(type default)
		)
	)
	(wire
		(pts
			(xy 113.03 60.96) (xy 106.68 60.96)
		)
		(stroke
			(width 0)
			(type default)
		)
	)
	(wire
		(pts
			(xy 203.2 34.29) (xy 204.47 34.29)
		)
		(stroke
			(width 0)
			(type default)
		)
	)
	(polyline
		(pts
			(xy 237.49 22.86) (xy 237.49 34.29)
		)
		(stroke
			(width 0)
			(type default)
		)
	)
	(bus
		(pts
			(xy 116.84 97.79) (xy 116.84 100.33)
		)
		(stroke
			(width 0)
			(type default)
		)
	)
	(wire
		(pts
			(xy 90.17 93.98) (xy 114.3 93.98)
		)
		(stroke
			(width 0)
			(type default)
		)
	)
	(bus
		(pts
			(xy 172.72 90.17) (xy 118.11 90.17)
		)
		(stroke
			(width 0)
			(type default)
		)
	)
	(wire
		(pts
			(xy 25.4 97.79) (xy 52.07 97.79)
		)
		(stroke
			(width 0)
			(type default)
		)
	)
	(bus
		(pts
			(xy 116.84 140.97) (xy 116.84 142.24)
		)
		(stroke
			(width 0)
			(type default)
		)
	)
	(wire
		(pts
			(xy 146.05 31.75) (xy 154.94 31.75)
		)
		(stroke
			(width 0)
			(type default)
		)
	)
	(bus
		(pts
			(xy 116.84 125.73) (xy 116.84 129.54)
		)
		(stroke
			(width 0)
			(type default)
		)
	)
	(bus
		(pts
			(xy 118.11 139.7) (xy 121.92 139.7)
		)
		(stroke
			(width 0)
			(type default)
		)
	)
	(bus
		(pts
			(xy 116.84 142.24) (xy 116.84 144.78)
		)
		(stroke
			(width 0)
			(type default)
		)
	)
	(wire
		(pts
			(xy 90.17 121.92) (xy 114.3 121.92)
		)
		(stroke
			(width 0)
			(type default)
		)
	)
	(wire
		(pts
			(xy 25.4 97.79) (xy 25.4 100.33)
		)
		(stroke
			(width 0)
			(type default)
		)
	)
	(wire
		(pts
			(xy 191.77 60.96) (xy 218.44 60.96)
		)
		(stroke
			(width 0)
			(type default)
		)
	)
	(wire
		(pts
			(xy 121.92 67.31) (xy 121.92 66.04)
		)
		(stroke
			(width 0)
			(type default)
		)
	)
	(wire
		(pts
			(xy 182.88 140.97) (xy 246.38 140.97)
		)
		(stroke
			(width 0)
			(type default)
		)
	)
	(bus
		(pts
			(xy 144.78 29.21) (xy 143.51 27.94)
		)
		(stroke
			(width 0)
			(type default)
		)
	)
	(wire
		(pts
			(xy 44.45 93.98) (xy 44.45 100.33)
		)
		(stroke
			(width 0)
			(type default)
		)
	)
	(wire
		(pts
			(xy 179.07 34.29) (xy 179.07 35.56)
		)
		(stroke
			(width 0)
			(type default)
		)
	)
	(wire
		(pts
			(xy 90.17 90.17) (xy 102.87 90.17)
		)
		(stroke
			(width 0)
			(type default)
		)
	)
	(wire
		(pts
			(xy 90.17 96.52) (xy 114.3 96.52)
		)
		(stroke
			(width 0)
			(type default)
		)
	)
	(label "PCIe_{x4}.TX2-"
		(at 93.98 115.57 0)
		(effects
			(font
				(size 1.27 1.27)
			)
			(justify left bottom)
		)
	)
	(label "PCIe_{x4}.TX0+"
		(at 184.15 125.73 0)
		(effects
			(font
				(size 1.27 1.27)
			)
			(justify left bottom)
		)
	)
	(label "PCIe_{x4}{PCIe}"
		(at 172.72 83.82 180)
		(effects
			(font
				(size 1.27 1.27)
			)
			(justify right bottom)
		)
	)
	(label "PCIe_{x4}.TX3-"
		(at 93.98 102.87 0)
		(effects
			(font
				(size 1.27 1.27)
			)
			(justify left bottom)
		)
	)
	(label "PCIe_{x4}.RX1+"
		(at 93.98 119.38 0)
		(effects
			(font
				(size 1.27 1.27)
			)
			(justify left bottom)
		)
	)
	(label "PCIe_{x4}.RX1-"
		(at 93.98 121.92 0)
		(effects
			(font
				(size 1.27 1.27)
			)
			(justify left bottom)
		)
	)
	(label "PCIe_{x4}.TX0-"
		(at 93.98 140.97 0)
		(effects
			(font
				(size 1.27 1.27)
			)
			(justify left bottom)
		)
	)
	(label "~{WAKE}"
		(at 33.02 100.33 180)
		(effects
			(font
				(size 1.27 1.27)
			)
			(justify right bottom)
		)
	)
	(label "~{CPRSNT}"
		(at 237.49 87.63 0)
		(effects
			(font
				(size 1.27 1.27)
			)
			(justify left bottom)
		)
	)
	(label "PCIe_{x4}.TX2+"
		(at 93.98 113.03 0)
		(effects
			(font
				(size 1.27 1.27)
			)
			(justify left bottom)
		)
	)
	(label "PCIe_{x4}.TX1-"
		(at 184.15 135.89 0)
		(effects
			(font
				(size 1.27 1.27)
			)
			(justify left bottom)
		)
	)
	(label "PCIe_{x4}.RX0-"
		(at 93.98 134.62 0)
		(effects
			(font
				(size 1.27 1.27)
			)
			(justify left bottom)
		)
	)
	(label "PCIe_{REF0}_R.CK+"
		(at 179.07 46.99 0)
		(effects
			(font
				(size 1.27 1.27)
			)
			(justify left bottom)
		)
	)
	(label "~{WAKEC}"
		(at 237.49 90.17 0)
		(effects
			(font
				(size 1.27 1.27)
			)
			(justify left bottom)
		)
	)
	(label "PCIe_{REF0}.CK-"
		(at 99.06 144.78 0)
		(effects
			(font
				(size 1.27 1.27)
			)
			(justify left bottom)
		)
	)
	(label "PCIe_{REF0}_R.CK-"
		(at 243.84 80.01 180)
		(effects
			(font
				(size 1.27 1.27)
			)
			(justify right bottom)
		)
	)
	(label "PCIe_{REF0}{PCIe_{REF}}"
		(at 121.92 139.7 0)
		(effects
			(font
				(size 1.27 1.27)
			)
			(justify left bottom)
		)
	)
	(label "~{PERSTC}"
		(at 237.49 85.09 0)
		(effects
			(font
				(size 1.27 1.27)
			)
			(justify left bottom)
		)
	)
	(label "PCIe_{x4}.TX1+"
		(at 184.15 133.35 0)
		(effects
			(font
				(size 1.27 1.27)
			)
			(justify left bottom)
		)
	)
	(label "PCIe_{x4}.TX1+"
		(at 93.98 125.73 0)
		(effects
			(font
				(size 1.27 1.27)
			)
			(justify left bottom)
		)
	)
	(label "PCIe_{x4}.RX3-"
		(at 184.15 120.65 0)
		(effects
			(font
				(size 1.27 1.27)
			)
			(justify left bottom)
		)
	)
	(label "~{WAKE}"
		(at 220.98 90.17 180)
		(effects
			(font
				(size 1.27 1.27)
			)
			(justify right bottom)
		)
	)
	(label "PCIe_{REF0}_R.CK-"
		(at 181.61 44.45 0)
		(effects
			(font
				(size 1.27 1.27)
			)
			(justify left bottom)
		)
	)
	(label "~{WAKE_C}_alt"
		(at 246.38 72.39 180)
		(effects
			(font
				(size 1.27 1.27)
			)
			(justify right bottom)
		)
	)
	(label "~{CPRSNT}"
		(at 181.61 22.86 180)
		(effects
			(font
				(size 1.27 1.27)
			)
			(justify right bottom)
		)
	)
	(label "PCIe_{x4}.RX3-"
		(at 93.98 96.52 0)
		(effects
			(font
				(size 1.27 1.27)
			)
			(justify left bottom)
		)
	)
	(label "PCIe_{x4}.RX1+"
		(at 184.15 102.87 0)
		(effects
			(font
				(size 1.27 1.27)
			)
			(justify left bottom)
		)
	)
	(label "~{WAKE_C}_alt"
		(at 203.2 22.86 180)
		(effects
			(font
				(size 1.27 1.27)
			)
			(justify right bottom)
		)
	)
	(label "PCIe_{REF0}.CK+"
		(at 99.06 147.32 0)
		(effects
			(font
				(size 1.27 1.27)
			)
			(justify left bottom)
		)
	)
	(label "PCIe_{x4}.TX2-"
		(at 184.15 143.51 0)
		(effects
			(font
				(size 1.27 1.27)
			)
			(justify left bottom)
		)
	)
	(label "PCIe_{x4}.TX0-"
		(at 184.15 128.27 0)
		(effects
			(font
				(size 1.27 1.27)
			)
			(justify left bottom)
		)
	)
	(label "PCIe_{x4}.TX0+"
		(at 93.98 138.43 0)
		(effects
			(font
				(size 1.27 1.27)
			)
			(justify left bottom)
		)
	)
	(label "~{PERST}"
		(at 220.98 85.09 180)
		(effects
			(font
				(size 1.27 1.27)
			)
			(justify right bottom)
		)
	)
	(label "~{PERST}"
		(at 33.02 95.25 180)
		(effects
			(font
				(size 1.27 1.27)
			)
			(justify right bottom)
		)
	)
	(label "~{PERSTC}"
		(at 179.07 25.4 180)
		(effects
			(font
				(size 1.27 1.27)
			)
			(justify right bottom)
		)
	)
	(label "PCIe_{x4}.RX1-"
		(at 184.15 105.41 0)
		(effects
			(font
				(size 1.27 1.27)
			)
			(justify left bottom)
		)
	)
	(label "PCIe_{REF0}{PCIe_{REF}}"
		(at 140.97 27.94 180)
		(effects
			(font
				(size 1.27 1.27)
			)
			(justify right bottom)
		)
	)
	(label "PCIe_{x4}.RX2-"
		(at 93.98 109.22 0)
		(effects
			(font
				(size 1.27 1.27)
			)
			(justify left bottom)
		)
	)
	(label "~{WAKEC}"
		(at 203.2 34.29 180)
		(effects
			(font
				(size 1.27 1.27)
			)
			(justify right bottom)
		)
	)
	(label "PCIe_{x4}.RX0+"
		(at 93.98 132.08 0)
		(effects
			(font
				(size 1.27 1.27)
			)
			(justify left bottom)
		)
	)
	(label "PCIe_{x4}.TX3+"
		(at 93.98 100.33 0)
		(effects
			(font
				(size 1.27 1.27)
			)
			(justify left bottom)
		)
	)
	(label "PCIe_{REF0}_R.CK+"
		(at 243.84 77.47 180)
		(effects
			(font
				(size 1.27 1.27)
			)
			(justify right bottom)
		)
	)
	(label "PCIe_{x4}.TX1-"
		(at 93.98 128.27 0)
		(effects
			(font
				(size 1.27 1.27)
			)
			(justify left bottom)
		)
	)
	(label "PCIe_{x4}.RX3+"
		(at 184.15 118.11 0)
		(effects
			(font
				(size 1.27 1.27)
			)
			(justify left bottom)
		)
	)
	(label "PCIe_{x4}.RX2-"
		(at 184.15 113.03 0)
		(effects
			(font
				(size 1.27 1.27)
			)
			(justify left bottom)
		)
	)
	(label "PCIe_{x4}.RX0-"
		(at 184.15 97.79 0)
		(effects
			(font
				(size 1.27 1.27)
			)
			(justify left bottom)
		)
	)
	(label "~{PERST}"
		(at 168.91 43.18 180)
		(effects
			(font
				(size 1.27 1.27)
			)
			(justify right bottom)
		)
	)
	(label "PCIe_{x4}.TX2+"
		(at 184.15 140.97 0)
		(effects
			(font
				(size 1.27 1.27)
			)
			(justify left bottom)
		)
	)
	(label "PCIe_{x4}.TX3+"
		(at 184.15 148.59 0)
		(effects
			(font
				(size 1.27 1.27)
			)
			(justify left bottom)
		)
	)
	(label "PCIe_{x4}.RX2+"
		(at 93.98 106.68 0)
		(effects
			(font
				(size 1.27 1.27)
			)
			(justify left bottom)
		)
	)
	(label "PCIe_{x4}.RX2+"
		(at 184.15 110.49 0)
		(effects
			(font
				(size 1.27 1.27)
			)
			(justify left bottom)
		)
	)
	(label "PCIe_{x4}.RX0+"
		(at 184.15 95.25 0)
		(effects
			(font
				(size 1.27 1.27)
			)
			(justify left bottom)
		)
	)
	(label "PCIe_{x4}.RX3+"
		(at 93.98 93.98 0)
		(effects
			(font
				(size 1.27 1.27)
			)
			(justify left bottom)
		)
	)
	(label "PCIe_{x4}.TX3-"
		(at 184.15 151.13 0)
		(effects
			(font
				(size 1.27 1.27)
			)
			(justify left bottom)
		)
	)
	(label "PCIe_{REF0}.CK-"
		(at 154.94 31.75 0)
		(effects
			(font
				(size 1.27 1.27)
			)
			(justify left bottom)
		)
	)
	(label "PCIe_{REF0}.CK+"
		(at 154.94 34.29 0)
		(effects
			(font
				(size 1.27 1.27)
			)
			(justify left bottom)
		)
	)
	(symbol
		(lib_id "Capacitors0402:C_100n_16V_X7R_0402")
		(at 227.33 71.12 90)
		(unit 1)
		(exclude_from_sim no)
		(in_bom yes)
		(on_board yes)
		(dnp no)
		(fields_autoplaced yes)
		(property "Reference" "C4"
			(at 229.87 67.3036 90)
			(effects
				(font
					(size 1.27 1.27)
					(thickness 0.15)
				)
				(justify right)
			)
		)
		(property "Value" "C_100n_16V_X7R_0402"
			(at 250.19 55.88 0)
			(effects
				(font
					(size 1.27 1.27)
					(thickness 0.15)
				)
				(justify left bottom)
				(hide yes)
			)
		)
		(property "Footprint" "antmicro-footprints:C_0402_1005Metric"
			(at 252.73 55.88 0)
			(effects
				(font
					(size 1.27 1.27)
					(thickness 0.15)
				)
				(justify left bottom)
				(hide yes)
			)
		)
		(property "Datasheet" "https://www.kemet.com/en/us/capacitors/product/C0402C104J4RAC7411.html"
			(at 255.27 55.88 0)
			(effects
				(font
					(size 1.27 1.27)
					(thickness 0.15)
				)
				(justify left bottom)
				(hide yes)
			)
		)
		(property "Description" "SMD Multilayer Ceramic Capacitor, 100nF, 50V, 0402, ±5%, X7R"
			(at 227.33 71.12 0)
			(effects
				(font
					(size 1.27 1.27)
				)
				(hide yes)
			)
		)
		(property "MPN" "C0402C104J4RAC7411"
			(at 257.81 55.88 0)
			(effects
				(font
					(size 1.27 1.27)
					(thickness 0.15)
				)
				(justify left bottom)
				(hide yes)
			)
		)
		(property "Val" "100n"
			(at 229.87 69.8436 90)
			(effects
				(font
					(size 1.27 1.27)
					(thickness 0.15)
				)
				(justify right)
			)
		)
		(property "Voltage" "16V"
			(at 237.49 55.88 0)
			(effects
				(font
					(size 1.27 1.27)
					(thickness 0.15)
				)
				(justify left bottom)
				(hide yes)
			)
		)
		(property "Dielectric" "X7R"
			(at 240.03 55.88 0)
			(effects
				(font
					(size 1.27 1.27)
					(thickness 0.15)
				)
				(justify left bottom)
				(hide yes)
			)
		)
		(property "Manufacturer" "KEMET"
			(at 242.57 55.88 0)
			(effects
				(font
					(size 1.27 1.27)
					(thickness 0.15)
				)
				(justify left bottom)
				(hide yes)
			)
		)
		(property "License" "Apache-2.0"
			(at 245.11 55.88 0)
			(effects
				(font
					(size 1.27 1.27)
					(thickness 0.15)
				)
				(justify left bottom)
				(hide yes)
			)
		)
		(property "Author" "Antmicro"
			(at 247.65 55.88 0)
			(effects
				(font
					(size 1.27 1.27)
					(thickness 0.15)
				)
				(justify left bottom)
				(hide yes)
			)
		)
		(pin "2"
		)
		(pin "1"
		)
		(instances
			(project ""
				(path ""
					(reference "C4")
					(unit 1)
				)
			)
		)
	)
	(symbol
		(lib_id "Capacitors0402:C_100n_16V_X7R_0402")
		(at 113.03 66.04 90)
		(unit 1)
		(exclude_from_sim no)
		(in_bom yes)
		(on_board yes)
		(dnp no)
		(fields_autoplaced yes)
		(property "Reference" "C1"
			(at 115.57 62.2236 90)
			(effects
				(font
					(size 1.27 1.27)
					(thickness 0.15)
				)
				(justify right)
			)
		)
		(property "Value" "C_100n_16V_X7R_0402"
			(at 135.89 50.8 0)
			(effects
				(font
					(size 1.27 1.27)
					(thickness 0.15)
				)
				(justify left bottom)
				(hide yes)
			)
		)
		(property "Footprint" "antmicro-footprints:C_0402_1005Metric"
			(at 138.43 50.8 0)
			(effects
				(font
					(size 1.27 1.27)
					(thickness 0.15)
				)
				(justify left bottom)
				(hide yes)
			)
		)
		(property "Datasheet" "https://www.kemet.com/en/us/capacitors/product/C0402C104J4RAC7411.html"
			(at 140.97 50.8 0)
			(effects
				(font
					(size 1.27 1.27)
					(thickness 0.15)
				)
				(justify left bottom)
				(hide yes)
			)
		)
		(property "Description" "SMD Multilayer Ceramic Capacitor, 100nF, 50V, 0402, ±5%, X7R"
			(at 113.03 66.04 0)
			(effects
				(font
					(size 1.27 1.27)
				)
				(hide yes)
			)
		)
		(property "MPN" "C0402C104J4RAC7411"
			(at 143.51 50.8 0)
			(effects
				(font
					(size 1.27 1.27)
					(thickness 0.15)
				)
				(justify left bottom)
				(hide yes)
			)
		)
		(property "Val" "100n"
			(at 115.57 64.7636 90)
			(effects
				(font
					(size 1.27 1.27)
					(thickness 0.15)
				)
				(justify right)
			)
		)
		(property "Voltage" "16V"
			(at 123.19 50.8 0)
			(effects
				(font
					(size 1.27 1.27)
					(thickness 0.15)
				)
				(justify left bottom)
				(hide yes)
			)
		)
		(property "Dielectric" "X7R"
			(at 125.73 50.8 0)
			(effects
				(font
					(size 1.27 1.27)
					(thickness 0.15)
				)
				(justify left bottom)
				(hide yes)
			)
		)
		(property "Manufacturer" "KEMET"
			(at 128.27 50.8 0)
			(effects
				(font
					(size 1.27 1.27)
					(thickness 0.15)
				)
				(justify left bottom)
				(hide yes)
			)
		)
		(property "License" "Apache-2.0"
			(at 130.81 50.8 0)
			(effects
				(font
					(size 1.27 1.27)
					(thickness 0.15)
				)
				(justify left bottom)
				(hide yes)
			)
		)
		(property "Author" "Antmicro"
			(at 133.35 50.8 0)
			(effects
				(font
					(size 1.27 1.27)
					(thickness 0.15)
				)
				(justify left bottom)
				(hide yes)
			)
		)
		(pin "2"
		)
		(pin "1"
		)
		(instances
			(project "antmicro-m2-oculink-adapter-hw"
				(path ""
					(reference "C1")
					(unit 1)
				)
			)
		)
	)
	(symbol
		(lib_id "Capacitors0402:C_100n_16V_X7R_0402")
		(at 121.92 66.04 90)
		(unit 1)
		(exclude_from_sim no)
		(in_bom yes)
		(on_board yes)
		(dnp no)
		(fields_autoplaced yes)
		(property "Reference" "C2"
			(at 124.46 62.2236 90)
			(effects
				(font
					(size 1.27 1.27)
					(thickness 0.15)
				)
				(justify right)
			)
		)
		(property "Value" "C_100n_16V_X7R_0402"
			(at 144.78 50.8 0)
			(effects
				(font
					(size 1.27 1.27)
					(thickness 0.15)
				)
				(justify left bottom)
				(hide yes)
			)
		)
		(property "Footprint" "antmicro-footprints:C_0402_1005Metric"
			(at 147.32 50.8 0)
			(effects
				(font
					(size 1.27 1.27)
					(thickness 0.15)
				)
				(justify left bottom)
				(hide yes)
			)
		)
		(property "Datasheet" "https://www.kemet.com/en/us/capacitors/product/C0402C104J4RAC7411.html"
			(at 149.86 50.8 0)
			(effects
				(font
					(size 1.27 1.27)
					(thickness 0.15)
				)
				(justify left bottom)
				(hide yes)
			)
		)
		(property "Description" "SMD Multilayer Ceramic Capacitor, 100nF, 50V, 0402, ±5%, X7R"
			(at 121.92 66.04 0)
			(effects
				(font
					(size 1.27 1.27)
				)
				(hide yes)
			)
		)
		(property "MPN" "C0402C104J4RAC7411"
			(at 152.4 50.8 0)
			(effects
				(font
					(size 1.27 1.27)
					(thickness 0.15)
				)
				(justify left bottom)
				(hide yes)
			)
		)
		(property "Val" "100n"
			(at 124.46 64.7636 90)
			(effects
				(font
					(size 1.27 1.27)
					(thickness 0.15)
				)
				(justify right)
			)
		)
		(property "Voltage" "16V"
			(at 132.08 50.8 0)
			(effects
				(font
					(size 1.27 1.27)
					(thickness 0.15)
				)
				(justify left bottom)
				(hide yes)
			)
		)
		(property "Dielectric" "X7R"
			(at 134.62 50.8 0)
			(effects
				(font
					(size 1.27 1.27)
					(thickness 0.15)
				)
				(justify left bottom)
				(hide yes)
			)
		)
		(property "Manufacturer" "KEMET"
			(at 137.16 50.8 0)
			(effects
				(font
					(size 1.27 1.27)
					(thickness 0.15)
				)
				(justify left bottom)
				(hide yes)
			)
		)
		(property "License" "Apache-2.0"
			(at 139.7 50.8 0)
			(effects
				(font
					(size 1.27 1.27)
					(thickness 0.15)
				)
				(justify left bottom)
				(hide yes)
			)
		)
		(property "Author" "Antmicro"
			(at 142.24 50.8 0)
			(effects
				(font
					(size 1.27 1.27)
					(thickness 0.15)
				)
				(justify left bottom)
				(hide yes)
			)
		)
		(pin "2"
		)
		(pin "1"
		)
		(instances
			(project "antmicro-m2-oculink-adapter-hw"
				(path ""
					(reference "C2")
					(unit 1)
				)
			)
		)
	)
	(symbol
		(lib_id "antmicroResistorsmisc:R_0R_0201")
		(at 181.61 33.02 90)
		(unit 1)
		(exclude_from_sim no)
		(in_bom yes)
		(on_board yes)
		(dnp yes)
		(fields_autoplaced yes)
		(property "Reference" "R5"
			(at 184.15 29.21 90)
			(effects
				(font
					(size 1.27 1.27)
					(thickness 0.15)
				)
				(justify right)
			)
		)
		(property "Value" "R_0R_0201"
			(at 194.31 12.7 0)
			(effects
				(font
					(size 1.27 1.27)
					(thickness 0.15)
				)
				(justify left bottom)
				(hide yes)
			)
		)
		(property "Footprint" "antmicro-footprints:R_0201"
			(at 196.85 12.7 0)
			(effects
				(font
					(size 1.27 1.27)
					(thickness 0.15)
				)
				(justify left bottom)
				(hide yes)
			)
		)
		(property "Datasheet" "https://www.bourns.com/docs/product-datasheets/cr.pdf"
			(at 199.39 12.7 0)
			(effects
				(font
					(size 1.27 1.27)
					(thickness 0.15)
				)
				(justify left bottom)
				(hide yes)
			)
		)
		(property "Description" "SMD Chip Resistor"
			(at 181.61 33.02 0)
			(effects
				(font
					(size 1.27 1.27)
				)
				(hide yes)
			)
		)
		(property "MPN" "CR0201-FX-0R00GLF"
			(at 201.93 12.7 0)
			(effects
				(font
					(size 1.27 1.27)
					(thickness 0.15)
				)
				(justify left bottom)
				(hide yes)
			)
		)
		(property "Manufacturer" "Bourns"
			(at 204.47 12.7 0)
			(effects
				(font
					(size 1.27 1.27)
					(thickness 0.15)
				)
				(justify left bottom)
				(hide yes)
			)
		)
		(property "License" "Apache-2.0"
			(at 207.01 12.7 0)
			(effects
				(font
					(size 1.27 1.27)
					(thickness 0.15)
				)
				(justify left bottom)
				(hide yes)
			)
		)
		(property "Author" "Antmicro"
			(at 209.55 12.7 0)
			(effects
				(font
					(size 1.27 1.27)
					(thickness 0.15)
				)
				(justify left bottom)
				(hide yes)
			)
		)
		(property "Val" "0R"
			(at 184.15 31.75 90)
			(effects
				(font
					(size 1.27 1.27)
					(thickness 0.15)
				)
				(justify right)
			)
		)
		(property "Tolerance" "1%"
			(at 191.77 12.7 0)
			(effects
				(font
					(size 1.27 1.27)
				)
				(justify left bottom)
				(hide yes)
			)
		)
		(pin "1"
		)
		(pin "2"
		)
		(instances
			(project "antmicro-m2-oculink-adapter-hw"
				(path ""
					(reference "R5")
					(unit 1)
				)
			)
		)
	)
	(symbol
		(lib_id "antmicroResistorsmisc:R_0R_0201")
		(at 226.06 85.09 0)
		(unit 1)
		(exclude_from_sim no)
		(in_bom yes)
		(on_board yes)
		(dnp no)
		(property "Reference" "R10"
			(at 225.298 83.312 0)
			(effects
				(font
					(size 1.27 1.27)
					(thickness 0.15)
				)
			)
		)
		(property "Value" "R_0R_0201"
			(at 246.38 97.79 0)
			(effects
				(font
					(size 1.27 1.27)
					(thickness 0.15)
				)
				(justify left bottom)
				(hide yes)
			)
		)
		(property "Footprint" "antmicro-footprints:R_0201"
			(at 246.38 100.33 0)
			(effects
				(font
					(size 1.27 1.27)
					(thickness 0.15)
				)
				(justify left bottom)
				(hide yes)
			)
		)
		(property "Datasheet" "https://www.bourns.com/docs/product-datasheets/cr.pdf"
			(at 246.38 102.87 0)
			(effects
				(font
					(size 1.27 1.27)
					(thickness 0.15)
				)
				(justify left bottom)
				(hide yes)
			)
		)
		(property "Description" "SMD Chip Resistor"
			(at 226.06 85.09 0)
			(effects
				(font
					(size 1.27 1.27)
				)
				(hide yes)
			)
		)
		(property "MPN" "CR0201-FX-0R00GLF"
			(at 246.38 105.41 0)
			(effects
				(font
					(size 1.27 1.27)
					(thickness 0.15)
				)
				(justify left bottom)
				(hide yes)
			)
		)
		(property "Manufacturer" "Bourns"
			(at 246.38 107.95 0)
			(effects
				(font
					(size 1.27 1.27)
					(thickness 0.15)
				)
				(justify left bottom)
				(hide yes)
			)
		)
		(property "License" "Apache-2.0"
			(at 246.38 110.49 0)
			(effects
				(font
					(size 1.27 1.27)
					(thickness 0.15)
				)
				(justify left bottom)
				(hide yes)
			)
		)
		(property "Author" "Antmicro"
			(at 246.38 113.03 0)
			(effects
				(font
					(size 1.27 1.27)
					(thickness 0.15)
				)
				(justify left bottom)
				(hide yes)
			)
		)
		(property "Val" "0R"
			(at 231.648 83.312 0)
			(effects
				(font
					(size 1.27 1.27)
					(thickness 0.15)
				)
			)
		)
		(property "Tolerance" "1%"
			(at 246.38 95.25 0)
			(effects
				(font
					(size 1.27 1.27)
				)
				(justify left bottom)
				(hide yes)
			)
		)
		(pin "1"
		)
		(pin "2"
		)
		(instances
			(project "antmicro-m2-oculink-adapter-hw"
				(path ""
					(reference "R10")
					(unit 1)
				)
			)
		)
	)
	(symbol
		(lib_id "antmicroResistorsmisc:R_0R_0201")
		(at 179.07 33.02 90)
		(unit 1)
		(exclude_from_sim no)
		(in_bom yes)
		(on_board yes)
		(dnp yes)
		(fields_autoplaced yes)
		(property "Reference" "R3"
			(at 176.53 29.21 90)
			(effects
				(font
					(size 1.27 1.27)
					(thickness 0.15)
				)
				(justify left)
			)
		)
		(property "Value" "R_0R_0201"
			(at 191.77 12.7 0)
			(effects
				(font
					(size 1.27 1.27)
					(thickness 0.15)
				)
				(justify left bottom)
				(hide yes)
			)
		)
		(property "Footprint" "antmicro-footprints:R_0201"
			(at 194.31 12.7 0)
			(effects
				(font
					(size 1.27 1.27)
					(thickness 0.15)
				)
				(justify left bottom)
				(hide yes)
			)
		)
		(property "Datasheet" "https://www.bourns.com/docs/product-datasheets/cr.pdf"
			(at 196.85 12.7 0)
			(effects
				(font
					(size 1.27 1.27)
					(thickness 0.15)
				)
				(justify left bottom)
				(hide yes)
			)
		)
		(property "Description" "SMD Chip Resistor"
			(at 179.07 33.02 0)
			(effects
				(font
					(size 1.27 1.27)
				)
				(hide yes)
			)
		)
		(property "MPN" "CR0201-FX-0R00GLF"
			(at 199.39 12.7 0)
			(effects
				(font
					(size 1.27 1.27)
					(thickness 0.15)
				)
				(justify left bottom)
				(hide yes)
			)
		)
		(property "Manufacturer" "Bourns"
			(at 201.93 12.7 0)
			(effects
				(font
					(size 1.27 1.27)
					(thickness 0.15)
				)
				(justify left bottom)
				(hide yes)
			)
		)
		(property "License" "Apache-2.0"
			(at 204.47 12.7 0)
			(effects
				(font
					(size 1.27 1.27)
					(thickness 0.15)
				)
				(justify left bottom)
				(hide yes)
			)
		)
		(property "Author" "Antmicro"
			(at 207.01 12.7 0)
			(effects
				(font
					(size 1.27 1.27)
					(thickness 0.15)
				)
				(justify left bottom)
				(hide yes)
			)
		)
		(property "Val" "0R"
			(at 176.53 31.75 90)
			(effects
				(font
					(size 1.27 1.27)
					(thickness 0.15)
				)
				(justify left)
			)
		)
		(property "Tolerance" "1%"
			(at 189.23 12.7 0)
			(effects
				(font
					(size 1.27 1.27)
				)
				(justify left bottom)
				(hide yes)
			)
		)
		(pin "1"
		)
		(pin "2"
		)
		(instances
			(project "antmicro-m2-oculink-adapter-hw"
				(path ""
					(reference "R3")
					(unit 1)
				)
			)
		)
	)
	(symbol
		(lib_id "antmicroResistorsmisc:R_0R_0201")
		(at 209.55 87.63 0)
		(unit 1)
		(exclude_from_sim no)
		(in_bom yes)
		(on_board yes)
		(dnp no)
		(property "Reference" "R13"
			(at 208.28 85.852 0)
			(effects
				(font
					(size 1.27 1.27)
					(thickness 0.15)
				)
			)
		)
		(property "Value" "R_0R_0201"
			(at 229.87 100.33 0)
			(effects
				(font
					(size 1.27 1.27)
					(thickness 0.15)
				)
				(justify left bottom)
				(hide yes)
			)
		)
		(property "Footprint" "antmicro-footprints:R_0201"
			(at 229.87 102.87 0)
			(effects
				(font
					(size 1.27 1.27)
					(thickness 0.15)
				)
				(justify left bottom)
				(hide yes)
			)
		)
		(property "Datasheet" "https://www.bourns.com/docs/product-datasheets/cr.pdf"
			(at 229.87 105.41 0)
			(effects
				(font
					(size 1.27 1.27)
					(thickness 0.15)
				)
				(justify left bottom)
				(hide yes)
			)
		)
		(property "Description" "SMD Chip Resistor"
			(at 209.55 87.63 0)
			(effects
				(font
					(size 1.27 1.27)
				)
				(hide yes)
			)
		)
		(property "MPN" "CR0201-FX-0R00GLF"
			(at 229.87 107.95 0)
			(effects
				(font
					(size 1.27 1.27)
					(thickness 0.15)
				)
				(justify left bottom)
				(hide yes)
			)
		)
		(property "Manufacturer" "Bourns"
			(at 229.87 110.49 0)
			(effects
				(font
					(size 1.27 1.27)
					(thickness 0.15)
				)
				(justify left bottom)
				(hide yes)
			)
		)
		(property "License" "Apache-2.0"
			(at 229.87 113.03 0)
			(effects
				(font
					(size 1.27 1.27)
					(thickness 0.15)
				)
				(justify left bottom)
				(hide yes)
			)
		)
		(property "Author" "Antmicro"
			(at 229.87 115.57 0)
			(effects
				(font
					(size 1.27 1.27)
					(thickness 0.15)
				)
				(justify left bottom)
				(hide yes)
			)
		)
		(property "Val" "0R"
			(at 215.138 85.852 0)
			(effects
				(font
					(size 1.27 1.27)
					(thickness 0.15)
				)
			)
		)
		(property "Tolerance" "1%"
			(at 229.87 97.79 0)
			(effects
				(font
					(size 1.27 1.27)
				)
				(justify left bottom)
				(hide yes)
			)
		)
		(pin "1"
		)
		(pin "2"
		)
		(instances
			(project "antmicro-m2-oculink-adapter-hw"
				(path ""
					(reference "R13")
					(unit 1)
				)
			)
		)
	)
	(symbol
		(lib_id "antmicroResistorsmisc:R_0R_0201")
		(at 181.61 40.64 90)
		(unit 1)
		(exclude_from_sim no)
		(in_bom yes)
		(on_board yes)
		(dnp no)
		(fields_autoplaced yes)
		(property "Reference" "R6"
			(at 184.15 36.83 90)
			(effects
				(font
					(size 1.27 1.27)
					(thickness 0.15)
				)
				(justify right)
			)
		)
		(property "Value" "R_0R_0201"
			(at 194.31 20.32 0)
			(effects
				(font
					(size 1.27 1.27)
					(thickness 0.15)
				)
				(justify left bottom)
				(hide yes)
			)
		)
		(property "Footprint" "antmicro-footprints:R_0201"
			(at 196.85 20.32 0)
			(effects
				(font
					(size 1.27 1.27)
					(thickness 0.15)
				)
				(justify left bottom)
				(hide yes)
			)
		)
		(property "Datasheet" "https://www.bourns.com/docs/product-datasheets/cr.pdf"
			(at 199.39 20.32 0)
			(effects
				(font
					(size 1.27 1.27)
					(thickness 0.15)
				)
				(justify left bottom)
				(hide yes)
			)
		)
		(property "Description" "SMD Chip Resistor"
			(at 181.61 40.64 0)
			(effects
				(font
					(size 1.27 1.27)
				)
				(hide yes)
			)
		)
		(property "MPN" "CR0201-FX-0R00GLF"
			(at 201.93 20.32 0)
			(effects
				(font
					(size 1.27 1.27)
					(thickness 0.15)
				)
				(justify left bottom)
				(hide yes)
			)
		)
		(property "Manufacturer" "Bourns"
			(at 204.47 20.32 0)
			(effects
				(font
					(size 1.27 1.27)
					(thickness 0.15)
				)
				(justify left bottom)
				(hide yes)
			)
		)
		(property "License" "Apache-2.0"
			(at 207.01 20.32 0)
			(effects
				(font
					(size 1.27 1.27)
					(thickness 0.15)
				)
				(justify left bottom)
				(hide yes)
			)
		)
		(property "Author" "Antmicro"
			(at 209.55 20.32 0)
			(effects
				(font
					(size 1.27 1.27)
					(thickness 0.15)
				)
				(justify left bottom)
				(hide yes)
			)
		)
		(property "Val" "0R"
			(at 184.15 39.37 90)
			(effects
				(font
					(size 1.27 1.27)
					(thickness 0.15)
				)
				(justify right)
			)
		)
		(property "Tolerance" "1%"
			(at 191.77 20.32 0)
			(effects
				(font
					(size 1.27 1.27)
				)
				(justify left bottom)
				(hide yes)
			)
		)
		(pin "1"
		)
		(pin "2"
		)
		(instances
			(project "antmicro-m2-oculink-adapter-hw"
				(path ""
					(reference "R6")
					(unit 1)
				)
			)
		)
	)
	(symbol
		(lib_id "antmicropower:GND")
		(at 274.32 153.67 0)
		(unit 1)
		(exclude_from_sim no)
		(in_bom yes)
		(on_board yes)
		(dnp no)
		(property "Reference" "#PWR06"
			(at 283.21 156.21 0)
			(effects
				(font
					(size 1.27 1.27)
					(thickness 0.15)
				)
				(justify left bottom)
				(hide yes)
			)
		)
		(property "Value" "GND"
			(at 274.32 157.48 0)
			(effects
				(font
					(size 1.27 1.27)
					(thickness 0.15)
				)
			)
		)
		(property "Footprint" ""
			(at 283.21 161.29 0)
			(effects
				(font
					(size 1.27 1.27)
					(thickness 0.15)
				)
				(justify left bottom)
				(hide yes)
			)
		)
		(property "Datasheet" ""
			(at 283.21 166.37 0)
			(effects
				(font
					(size 1.27 1.27)
					(thickness 0.15)
				)
				(justify left bottom)
				(hide yes)
			)
		)
		(property "Description" ""
			(at 274.32 153.67 0)
			(effects
				(font
					(size 1.27 1.27)
				)
				(hide yes)
			)
		)
		(property "Author" "Antmicro"
			(at 283.21 161.29 0)
			(effects
				(font
					(size 1.27 1.27)
					(thickness 0.15)
				)
				(justify left bottom)
				(hide yes)
			)
		)
		(property "License" "Apache-2.0"
			(at 283.21 163.83 0)
			(effects
				(font
					(size 1.27 1.27)
					(thickness 0.15)
				)
				(justify left bottom)
				(hide yes)
			)
		)
		(pin "1"
		)
		(instances
			(project "antmicro-m2-oculink-adapter-hw"
				(path ""
					(reference "#PWR06")
					(unit 1)
				)
			)
		)
	)
	(symbol
		(lib_id "EdgeConnectors:PCB-Edge_M.2_Key-M")
		(at 90.17 90.17 0)
		(mirror y)
		(unit 1)
		(exclude_from_sim no)
		(in_bom no)
		(on_board yes)
		(dnp no)
		(fields_autoplaced yes)
		(property "Reference" "J1"
			(at 71.12 82.55 0)
			(effects
				(font
					(size 1.27 1.27)
					(thickness 0.15)
				)
			)
		)
		(property "Value" "PCB-Edge_M.2_Key-M"
			(at 71.12 85.09 0)
			(effects
				(font
					(size 1.27 1.27)
					(thickness 0.15)
				)
			)
		)
		(property "Footprint" "antmicro-footprints:PCB-Edge_M.2_Key-M"
			(at 36.83 97.79 0)
			(effects
				(font
					(size 1.27 1.27)
					(thickness 0.15)
				)
				(justify left bottom)
				(hide yes)
			)
		)
		(property "Datasheet" "https://www.amphenol-icc.com/media/wysiwyg/files/drawing/10130618.pdf"
			(at 36.83 100.33 0)
			(effects
				(font
					(size 1.27 1.27)
					(thickness 0.15)
				)
				(justify left bottom)
				(hide yes)
			)
		)
		(property "Description" "PCB Edge for M.2 key M"
			(at 90.17 90.17 0)
			(effects
				(font
					(size 1.27 1.27)
				)
				(hide yes)
			)
		)
		(property "Author" "Antmicro"
			(at 36.83 102.87 0)
			(effects
				(font
					(size 1.27 1.27)
					(thickness 0.15)
				)
				(justify left bottom)
				(hide yes)
			)
		)
		(property "License" "Apache-2.0"
			(at 36.83 105.41 0)
			(effects
				(font
					(size 1.27 1.27)
					(thickness 0.15)
				)
				(justify left bottom)
				(hide yes)
			)
		)
		(pin "75"
		)
		(pin "74"
		)
		(pin "68"
		)
		(pin "56"
		)
		(pin "28"
		)
		(pin "12"
		)
		(pin "33"
		)
		(pin "30"
		)
		(pin "15"
		)
		(pin "32"
		)
		(pin "50"
		)
		(pin "9"
		)
		(pin "20"
		)
		(pin "44"
		)
		(pin "4"
		)
		(pin "6"
		)
		(pin "7"
		)
		(pin "34"
		)
		(pin "29"
		)
		(pin "36"
		)
		(pin "40"
		)
		(pin "16"
		)
		(pin "14"
		)
		(pin "71"
		)
		(pin "39"
		)
		(pin "48"
		)
		(pin "24"
		)
		(pin "2"
		)
		(pin "52"
		)
		(pin "43"
			(alternate "PERp0")
		)
		(pin "21"
		)
		(pin "67"
		)
		(pin "70"
		)
		(pin "53"
		)
		(pin "38"
		)
		(pin "55"
		)
		(pin "1"
		)
		(pin "49"
			(alternate "PETp0")
		)
		(pin "23"
		)
		(pin "73"
		)
		(pin "54"
		)
		(pin "18"
		)
		(pin "22"
		)
		(pin "45"
		)
		(pin "19"
		)
		(pin "25"
		)
		(pin "27"
		)
		(pin "17"
		)
		(pin "46"
		)
		(pin "57"
		)
		(pin "8"
		)
		(pin "31"
		)
		(pin "3"
		)
		(pin "26"
		)
		(pin "11"
		)
		(pin "10"
		)
		(pin "35"
		)
		(pin "5"
		)
		(pin "42"
		)
		(pin "13"
		)
		(pin "51"
		)
		(pin "41"
			(alternate "PERn0")
		)
		(pin "47"
			(alternate "PETn0")
		)
		(pin "58"
		)
		(pin "37"
		)
		(pin "69"
		)
		(pin "72"
		)
		(instances
			(project ""
				(path ""
					(reference "J1")
					(unit 1)
				)
			)
		)
	)
	(symbol
		(lib_id "antmicroTestPoints:TP_1mm_SMD")
		(at 204.47 86.36 90)
		(unit 1)
		(exclude_from_sim no)
		(in_bom no)
		(on_board yes)
		(dnp no)
		(fields_autoplaced yes)
		(property "Reference" "TP3"
			(at 207.01 83.185 90)
			(effects
				(font
					(size 1.27 1.27)
					(thickness 0.15)
				)
				(justify right)
			)
		)
		(property "Value" "TP_1mm_SMD"
			(at 212.09 71.12 0)
			(effects
				(font
					(size 1.27 1.27)
					(thickness 0.15)
				)
				(justify left bottom)
				(hide yes)
			)
		)
		(property "Footprint" "antmicro-footprints:TP_SMD_1mm"
			(at 214.63 71.12 0)
			(effects
				(font
					(size 1.27 1.27)
					(thickness 0.15)
				)
				(justify left bottom)
				(hide yes)
			)
		)
		(property "Datasheet" ""
			(at 217.17 68.58 0)
			(effects
				(font
					(size 1.27 1.27)
					(thickness 0.15)
				)
				(justify left bottom)
				(hide yes)
			)
		)
		(property "Description" "Test point 1mm SMD"
			(at 204.47 86.36 0)
			(effects
				(font
					(size 1.27 1.27)
				)
				(hide yes)
			)
		)
		(property "MPN" ""
			(at 204.47 86.36 0)
			(effects
				(font
					(size 1.27 1.27)
				)
				(hide yes)
			)
		)
		(property "Manufacturer" ""
			(at 204.47 86.36 0)
			(effects
				(font
					(size 1.27 1.27)
				)
				(hide yes)
			)
		)
		(property "Author" "Antmicro"
			(at 219.71 71.12 0)
			(effects
				(font
					(size 1.27 1.27)
					(thickness 0.15)
				)
				(justify left bottom)
				(hide yes)
			)
		)
		(property "License" "Apache-2.0"
			(at 222.25 71.12 0)
			(effects
				(font
					(size 1.27 1.27)
					(thickness 0.15)
				)
				(justify left bottom)
				(hide yes)
			)
		)
		(pin "1"
		)
		(instances
			(project ""
				(path ""
					(reference "TP3")
					(unit 1)
				)
			)
		)
	)
	(symbol
		(lib_id "Resistors0402:R_0R_0402")
		(at 154.94 64.77 0)
		(unit 1)
		(exclude_from_sim no)
		(in_bom yes)
		(on_board yes)
		(dnp no)
		(fields_autoplaced yes)
		(property "Reference" "R7"
			(at 157.48 68.58 0)
			(effects
				(font
					(size 1.27 1.27)
					(thickness 0.15)
				)
			)
		)
		(property "Value" "R_0R_0402"
			(at 175.26 77.47 0)
			(effects
				(font
					(size 1.27 1.27)
					(thickness 0.15)
				)
				(justify left bottom)
				(hide yes)
			)
		)
		(property "Footprint" "antmicro-footprints:R_0402_1005Metric"
			(at 175.26 80.01 0)
			(effects
				(font
					(size 1.27 1.27)
					(thickness 0.15)
				)
				(justify left bottom)
				(hide yes)
			)
		)
		(property "Datasheet" "https://industrial.panasonic.com/cdbs/www-data/pdf/RDA0000/AOA0000C301.pdf"
			(at 175.26 82.55 0)
			(effects
				(font
					(size 1.27 1.27)
					(thickness 0.15)
				)
				(justify left bottom)
				(hide yes)
			)
		)
		(property "Description" "SMD Chip Resistor, Jumper, 0 ohm, 100 mW, 0402 [1005 Metric], Thick Film, General Purpose"
			(at 154.94 64.77 0)
			(effects
				(font
					(size 1.27 1.27)
				)
				(hide yes)
			)
		)
		(property "MPN" "ERJ2GE0R00X"
			(at 175.26 85.09 0)
			(effects
				(font
					(size 1.27 1.27)
					(thickness 0.15)
				)
				(justify left bottom)
				(hide yes)
			)
		)
		(property "Manufacturer" "Panasonic"
			(at 175.26 87.63 0)
			(effects
				(font
					(size 1.27 1.27)
					(thickness 0.15)
				)
				(justify left bottom)
				(hide yes)
			)
		)
		(property "License" "Apache-2.0"
			(at 175.26 90.17 0)
			(effects
				(font
					(size 1.27 1.27)
					(thickness 0.15)
				)
				(justify left bottom)
				(hide yes)
			)
		)
		(property "Author" "Antmicro"
			(at 175.26 92.71 0)
			(effects
				(font
					(size 1.27 1.27)
					(thickness 0.15)
				)
				(justify left bottom)
				(hide yes)
			)
		)
		(property "Val" "0R"
			(at 157.48 71.12 0)
			(effects
				(font
					(size 1.27 1.27)
					(thickness 0.15)
				)
			)
		)
		(property "Tolerance" "~"
			(at 175.26 74.93 0)
			(effects
				(font
					(size 1.27 1.27)
				)
				(justify left bottom)
				(hide yes)
			)
		)
		(property "Current" "1A"
			(at 175.26 95.25 0)
			(effects
				(font
					(size 1.27 1.27)
					(thickness 0.15)
				)
				(justify left bottom)
				(hide yes)
			)
		)
		(pin "2"
		)
		(pin "1"
		)
		(instances
			(project "antmicro-m2-oculink-adapter-hw"
				(path ""
					(reference "R7")
					(unit 1)
				)
			)
		)
	)
	(symbol
		(lib_id "antmicroResistors0402:R_0R_0402")
		(at 25.4 100.33 90)
		(mirror x)
		(unit 1)
		(exclude_from_sim no)
		(in_bom yes)
		(on_board yes)
		(dnp no)
		(fields_autoplaced yes)
		(property "Reference" "R1"
			(at 22.86 101.6 90)
			(effects
				(font
					(size 1.27 1.27)
					(thickness 0.15)
				)
				(justify left)
			)
		)
		(property "Value" "R_0R_0402"
			(at 38.1 120.65 0)
			(effects
				(font
					(size 1.27 1.27)
					(thickness 0.15)
				)
				(justify left bottom)
				(hide yes)
			)
		)
		(property "Footprint" "antmicro-footprints:R_0402_1005Metric"
			(at 40.64 120.65 0)
			(effects
				(font
					(size 1.27 1.27)
					(thickness 0.15)
				)
				(justify left bottom)
				(hide yes)
			)
		)
		(property "Datasheet" "https://industrial.panasonic.com/cdbs/www-data/pdf/RDA0000/AOA0000C301.pdf"
			(at 43.18 120.65 0)
			(effects
				(font
					(size 1.27 1.27)
					(thickness 0.15)
				)
				(justify left bottom)
				(hide yes)
			)
		)
		(property "Description" "SMD Chip Resistor, Jumper, 0 ohm, 100 mW, 0402 [1005 Metric], Thick Film, General Purpose"
			(at 25.4 100.33 0)
			(effects
				(font
					(size 1.27 1.27)
				)
				(hide yes)
			)
		)
		(property "MPN" "ERJ2GE0R00X"
			(at 45.72 120.65 0)
			(effects
				(font
					(size 1.27 1.27)
					(thickness 0.15)
				)
				(justify left bottom)
				(hide yes)
			)
		)
		(property "Manufacturer" "Panasonic"
			(at 48.26 120.65 0)
			(effects
				(font
					(size 1.27 1.27)
					(thickness 0.15)
				)
				(justify left bottom)
				(hide yes)
			)
		)
		(property "License" "Apache-2.0"
			(at 50.8 120.65 0)
			(effects
				(font
					(size 1.27 1.27)
					(thickness 0.15)
				)
				(justify left bottom)
				(hide yes)
			)
		)
		(property "Author" "Antmicro"
			(at 53.34 120.65 0)
			(effects
				(font
					(size 1.27 1.27)
					(thickness 0.15)
				)
				(justify left bottom)
				(hide yes)
			)
		)
		(property "Val" "0R"
			(at 22.86 104.14 90)
			(effects
				(font
					(size 1.27 1.27)
					(thickness 0.15)
				)
				(justify left)
			)
		)
		(property "Tolerance" "~"
			(at 35.56 120.65 0)
			(effects
				(font
					(size 1.27 1.27)
				)
				(justify left bottom)
				(hide yes)
			)
		)
		(property "Current" "1A"
			(at 55.88 120.65 0)
			(effects
				(font
					(size 1.27 1.27)
					(thickness 0.15)
				)
				(justify left bottom)
				(hide yes)
			)
		)
		(pin "1"
		)
		(pin "2"
		)
		(instances
			(project "antmicro-m2-oculink-adapter-hw"
				(path ""
					(reference "R1")
					(unit 1)
				)
			)
		)
	)
	(symbol
		(lib_id "power:+3V3")
		(at 191.77 60.96 0)
		(unit 1)
		(exclude_from_sim no)
		(in_bom yes)
		(on_board yes)
		(dnp no)
		(fields_autoplaced yes)
		(property "Reference" "#PWR04"
			(at 207.01 60.96 0)
			(effects
				(font
					(size 1.27 1.27)
					(thickness 0.15)
				)
				(justify left bottom)
				(hide yes)
			)
		)
		(property "Value" "+3V3"
			(at 191.77 55.88 0)
			(effects
				(font
					(size 1.27 1.27)
					(thickness 0.15)
				)
			)
		)
		(property "Footprint" ""
			(at 207.01 68.58 0)
			(effects
				(font
					(size 1.27 1.27)
					(thickness 0.15)
				)
				(justify left bottom)
				(hide yes)
			)
		)
		(property "Datasheet" ""
			(at 207.01 71.12 0)
			(effects
				(font
					(size 1.27 1.27)
					(thickness 0.15)
				)
				(justify left bottom)
				(hide yes)
			)
		)
		(property "Description" ""
			(at 191.77 60.96 0)
			(effects
				(font
					(size 1.27 1.27)
				)
				(hide yes)
			)
		)
		(property "Author" "Antmicro"
			(at 207.01 63.5 0)
			(effects
				(font
					(size 1.27 1.27)
					(thickness 0.15)
				)
				(justify left bottom)
				(hide yes)
			)
		)
		(property "License" "Apache-2.0"
			(at 207.01 66.04 0)
			(effects
				(font
					(size 1.27 1.27)
					(thickness 0.15)
				)
				(justify left bottom)
				(hide yes)
			)
		)
		(pin "1"
		)
		(instances
			(project ""
				(path ""
					(reference "#PWR04")
					(unit 1)
				)
			)
		)
	)
	(symbol
		(lib_id "antmicroResistors0402:R_0R_0402")
		(at 231.14 90.17 0)
		(mirror y)
		(unit 1)
		(exclude_from_sim no)
		(in_bom yes)
		(on_board yes)
		(dnp no)
		(property "Reference" "R11"
			(at 232.918 88.9 0)
			(effects
				(font
					(size 1.27 1.27)
					(thickness 0.15)
				)
			)
		)
		(property "Value" "R_0R_0402"
			(at 210.82 102.87 0)
			(effects
				(font
					(size 1.27 1.27)
					(thickness 0.15)
				)
				(justify left bottom)
				(hide yes)
			)
		)
		(property "Footprint" "antmicro-footprints:R_0402_1005Metric"
			(at 210.82 105.41 0)
			(effects
				(font
					(size 1.27 1.27)
					(thickness 0.15)
				)
				(justify left bottom)
				(hide yes)
			)
		)
		(property "Datasheet" "https://industrial.panasonic.com/cdbs/www-data/pdf/RDA0000/AOA0000C301.pdf"
			(at 210.82 107.95 0)
			(effects
				(font
					(size 1.27 1.27)
					(thickness 0.15)
				)
				(justify left bottom)
				(hide yes)
			)
		)
		(property "Description" "SMD Chip Resistor, Jumper, 0 ohm, 100 mW, 0402 [1005 Metric], Thick Film, General Purpose"
			(at 231.14 90.17 0)
			(effects
				(font
					(size 1.27 1.27)
				)
				(hide yes)
			)
		)
		(property "MPN" "ERJ2GE0R00X"
			(at 210.82 110.49 0)
			(effects
				(font
					(size 1.27 1.27)
					(thickness 0.15)
				)
				(justify left bottom)
				(hide yes)
			)
		)
		(property "Manufacturer" "Panasonic"
			(at 210.82 113.03 0)
			(effects
				(font
					(size 1.27 1.27)
					(thickness 0.15)
				)
				(justify left bottom)
				(hide yes)
			)
		)
		(property "License" "Apache-2.0"
			(at 210.82 115.57 0)
			(effects
				(font
					(size 1.27 1.27)
					(thickness 0.15)
				)
				(justify left bottom)
				(hide yes)
			)
		)
		(property "Author" "Antmicro"
			(at 210.82 118.11 0)
			(effects
				(font
					(size 1.27 1.27)
					(thickness 0.15)
				)
				(justify left bottom)
				(hide yes)
			)
		)
		(property "Val" "0R"
			(at 225.044 88.9 0)
			(effects
				(font
					(size 1.27 1.27)
					(thickness 0.15)
				)
			)
		)
		(property "Tolerance" "~"
			(at 210.82 100.33 0)
			(effects
				(font
					(size 1.27 1.27)
				)
				(justify left bottom)
				(hide yes)
			)
		)
		(property "Current" "1A"
			(at 210.82 120.65 0)
			(effects
				(font
					(size 1.27 1.27)
					(thickness 0.15)
				)
				(justify left bottom)
				(hide yes)
			)
		)
		(pin "1"
		)
		(pin "2"
		)
		(instances
			(project "antmicro-m2-oculink-adapter-hw"
				(path ""
					(reference "R11")
					(unit 1)
				)
			)
		)
	)
	(symbol
		(lib_id "Capacitors0402:C_100n_16V_X7R_0402")
		(at 218.44 71.12 90)
		(unit 1)
		(exclude_from_sim no)
		(in_bom yes)
		(on_board yes)
		(dnp no)
		(fields_autoplaced yes)
		(property "Reference" "C3"
			(at 220.98 67.3036 90)
			(effects
				(font
					(size 1.27 1.27)
					(thickness 0.15)
				)
				(justify right)
			)
		)
		(property "Value" "C_100n_16V_X7R_0402"
			(at 241.3 55.88 0)
			(effects
				(font
					(size 1.27 1.27)
					(thickness 0.15)
				)
				(justify left bottom)
				(hide yes)
			)
		)
		(property "Footprint" "antmicro-footprints:C_0402_1005Metric"
			(at 243.84 55.88 0)
			(effects
				(font
					(size 1.27 1.27)
					(thickness 0.15)
				)
				(justify left bottom)
				(hide yes)
			)
		)
		(property "Datasheet" "https://www.kemet.com/en/us/capacitors/product/C0402C104J4RAC7411.html"
			(at 246.38 55.88 0)
			(effects
				(font
					(size 1.27 1.27)
					(thickness 0.15)
				)
				(justify left bottom)
				(hide yes)
			)
		)
		(property "Description" "SMD Multilayer Ceramic Capacitor, 100nF, 50V, 0402, ±5%, X7R"
			(at 218.44 71.12 0)
			(effects
				(font
					(size 1.27 1.27)
				)
				(hide yes)
			)
		)
		(property "MPN" "C0402C104J4RAC7411"
			(at 248.92 55.88 0)
			(effects
				(font
					(size 1.27 1.27)
					(thickness 0.15)
				)
				(justify left bottom)
				(hide yes)
			)
		)
		(property "Val" "100n"
			(at 220.98 69.8436 90)
			(effects
				(font
					(size 1.27 1.27)
					(thickness 0.15)
				)
				(justify right)
			)
		)
		(property "Voltage" "16V"
			(at 228.6 55.88 0)
			(effects
				(font
					(size 1.27 1.27)
					(thickness 0.15)
				)
				(justify left bottom)
				(hide yes)
			)
		)
		(property "Dielectric" "X7R"
			(at 231.14 55.88 0)
			(effects
				(font
					(size 1.27 1.27)
					(thickness 0.15)
				)
				(justify left bottom)
				(hide yes)
			)
		)
		(property "Manufacturer" "KEMET"
			(at 233.68 55.88 0)
			(effects
				(font
					(size 1.27 1.27)
					(thickness 0.15)
				)
				(justify left bottom)
				(hide yes)
			)
		)
		(property "License" "Apache-2.0"
			(at 236.22 55.88 0)
			(effects
				(font
					(size 1.27 1.27)
					(thickness 0.15)
				)
				(justify left bottom)
				(hide yes)
			)
		)
		(property "Author" "Antmicro"
			(at 238.76 55.88 0)
			(effects
				(font
					(size 1.27 1.27)
					(thickness 0.15)
				)
				(justify left bottom)
				(hide yes)
			)
		)
		(pin "2"
		)
		(pin "1"
		)
		(instances
			(project "antmicro-m2-oculink-adapter-hw"
				(path ""
					(reference "C3")
					(unit 1)
				)
			)
		)
	)
	(symbol
		(lib_id "antmicropower:GND")
		(at 113.03 67.31 0)
		(unit 1)
		(exclude_from_sim no)
		(in_bom yes)
		(on_board yes)
		(dnp no)
		(property "Reference" "#PWR03"
			(at 121.92 69.85 0)
			(effects
				(font
					(size 1.27 1.27)
					(thickness 0.15)
				)
				(justify left bottom)
				(hide yes)
			)
		)
		(property "Value" "GND"
			(at 113.03 71.12 0)
			(effects
				(font
					(size 1.27 1.27)
					(thickness 0.15)
				)
			)
		)
		(property "Footprint" ""
			(at 121.92 74.93 0)
			(effects
				(font
					(size 1.27 1.27)
					(thickness 0.15)
				)
				(justify left bottom)
				(hide yes)
			)
		)
		(property "Datasheet" ""
			(at 121.92 80.01 0)
			(effects
				(font
					(size 1.27 1.27)
					(thickness 0.15)
				)
				(justify left bottom)
				(hide yes)
			)
		)
		(property "Description" ""
			(at 113.03 67.31 0)
			(effects
				(font
					(size 1.27 1.27)
				)
				(hide yes)
			)
		)
		(property "Author" "Antmicro"
			(at 121.92 74.93 0)
			(effects
				(font
					(size 1.27 1.27)
					(thickness 0.15)
				)
				(justify left bottom)
				(hide yes)
			)
		)
		(property "License" "Apache-2.0"
			(at 121.92 77.47 0)
			(effects
				(font
					(size 1.27 1.27)
					(thickness 0.15)
				)
				(justify left bottom)
				(hide yes)
			)
		)
		(pin "1"
		)
		(instances
			(project "antmicro-m2-oculink-adapter-hw"
				(path ""
					(reference "#PWR03")
					(unit 1)
				)
			)
		)
	)
	(symbol
		(lib_id "antmicropower:GND")
		(at 50.8 152.4 0)
		(mirror y)
		(unit 1)
		(exclude_from_sim no)
		(in_bom yes)
		(on_board yes)
		(dnp no)
		(property "Reference" "#PWR02"
			(at 41.91 154.94 0)
			(effects
				(font
					(size 1.27 1.27)
					(thickness 0.15)
				)
				(justify left bottom)
				(hide yes)
			)
		)
		(property "Value" "GND"
			(at 50.8 156.21 0)
			(effects
				(font
					(size 1.27 1.27)
					(thickness 0.15)
				)
			)
		)
		(property "Footprint" ""
			(at 41.91 160.02 0)
			(effects
				(font
					(size 1.27 1.27)
					(thickness 0.15)
				)
				(justify left bottom)
				(hide yes)
			)
		)
		(property "Datasheet" ""
			(at 41.91 165.1 0)
			(effects
				(font
					(size 1.27 1.27)
					(thickness 0.15)
				)
				(justify left bottom)
				(hide yes)
			)
		)
		(property "Description" ""
			(at 50.8 152.4 0)
			(effects
				(font
					(size 1.27 1.27)
				)
				(hide yes)
			)
		)
		(property "Author" "Antmicro"
			(at 41.91 160.02 0)
			(effects
				(font
					(size 1.27 1.27)
					(thickness 0.15)
				)
				(justify left bottom)
				(hide yes)
			)
		)
		(property "License" "Apache-2.0"
			(at 41.91 162.56 0)
			(effects
				(font
					(size 1.27 1.27)
					(thickness 0.15)
				)
				(justify left bottom)
				(hide yes)
			)
		)
		(pin "1"
		)
		(instances
			(project "antmicro-m2-oculink-adapter-hw"
				(path ""
					(reference "#PWR02")
					(unit 1)
				)
			)
		)
	)
	(symbol
		(lib_id "antmicroResistorsmisc:R_0R_0201")
		(at 179.07 40.64 90)
		(unit 1)
		(exclude_from_sim no)
		(in_bom yes)
		(on_board yes)
		(dnp no)
		(fields_autoplaced yes)
		(property "Reference" "R4"
			(at 176.53 36.83 90)
			(effects
				(font
					(size 1.27 1.27)
					(thickness 0.15)
				)
				(justify left)
			)
		)
		(property "Value" "R_0R_0201"
			(at 191.77 20.32 0)
			(effects
				(font
					(size 1.27 1.27)
					(thickness 0.15)
				)
				(justify left bottom)
				(hide yes)
			)
		)
		(property "Footprint" "antmicro-footprints:R_0201"
			(at 194.31 20.32 0)
			(effects
				(font
					(size 1.27 1.27)
					(thickness 0.15)
				)
				(justify left bottom)
				(hide yes)
			)
		)
		(property "Datasheet" "https://www.bourns.com/docs/product-datasheets/cr.pdf"
			(at 196.85 20.32 0)
			(effects
				(font
					(size 1.27 1.27)
					(thickness 0.15)
				)
				(justify left bottom)
				(hide yes)
			)
		)
		(property "Description" "SMD Chip Resistor"
			(at 179.07 40.64 0)
			(effects
				(font
					(size 1.27 1.27)
				)
				(hide yes)
			)
		)
		(property "MPN" "CR0201-FX-0R00GLF"
			(at 199.39 20.32 0)
			(effects
				(font
					(size 1.27 1.27)
					(thickness 0.15)
				)
				(justify left bottom)
				(hide yes)
			)
		)
		(property "Manufacturer" "Bourns"
			(at 201.93 20.32 0)
			(effects
				(font
					(size 1.27 1.27)
					(thickness 0.15)
				)
				(justify left bottom)
				(hide yes)
			)
		)
		(property "License" "Apache-2.0"
			(at 204.47 20.32 0)
			(effects
				(font
					(size 1.27 1.27)
					(thickness 0.15)
				)
				(justify left bottom)
				(hide yes)
			)
		)
		(property "Author" "Antmicro"
			(at 207.01 20.32 0)
			(effects
				(font
					(size 1.27 1.27)
					(thickness 0.15)
				)
				(justify left bottom)
				(hide yes)
			)
		)
		(property "Val" "0R"
			(at 176.53 39.37 90)
			(effects
				(font
					(size 1.27 1.27)
					(thickness 0.15)
				)
				(justify left)
			)
		)
		(property "Tolerance" "1%"
			(at 189.23 20.32 0)
			(effects
				(font
					(size 1.27 1.27)
				)
				(justify left bottom)
				(hide yes)
			)
		)
		(pin "1"
		)
		(pin "2"
		)
		(instances
			(project "antmicro-m2-oculink-adapter-hw"
				(path ""
					(reference "R4")
					(unit 1)
				)
			)
		)
	)
	(symbol
		(lib_id "antmicropower:GND")
		(at 25.4 107.95 0)
		(mirror y)
		(unit 1)
		(exclude_from_sim no)
		(in_bom yes)
		(on_board yes)
		(dnp no)
		(property "Reference" "#PWR01"
			(at 16.51 110.49 0)
			(effects
				(font
					(size 1.27 1.27)
					(thickness 0.15)
				)
				(justify left bottom)
				(hide yes)
			)
		)
		(property "Value" "GND"
			(at 25.4 111.76 0)
			(effects
				(font
					(size 1.27 1.27)
					(thickness 0.15)
				)
			)
		)
		(property "Footprint" ""
			(at 16.51 115.57 0)
			(effects
				(font
					(size 1.27 1.27)
					(thickness 0.15)
				)
				(justify left bottom)
				(hide yes)
			)
		)
		(property "Datasheet" ""
			(at 16.51 120.65 0)
			(effects
				(font
					(size 1.27 1.27)
					(thickness 0.15)
				)
				(justify left bottom)
				(hide yes)
			)
		)
		(property "Description" ""
			(at 25.4 107.95 0)
			(effects
				(font
					(size 1.27 1.27)
				)
				(hide yes)
			)
		)
		(property "Author" "Antmicro"
			(at 16.51 115.57 0)
			(effects
				(font
					(size 1.27 1.27)
					(thickness 0.15)
				)
				(justify left bottom)
				(hide yes)
			)
		)
		(property "License" "Apache-2.0"
			(at 16.51 118.11 0)
			(effects
				(font
					(size 1.27 1.27)
					(thickness 0.15)
				)
				(justify left bottom)
				(hide yes)
			)
		)
		(pin "1"
		)
		(instances
			(project "antmicro-m2-oculink-adapter-hw"
				(path ""
					(reference "#PWR01")
					(unit 1)
				)
			)
		)
	)
	(symbol
		(lib_id "antmicroResistorsmisc:R_0R_0201")
		(at 204.47 31.75 90)
		(unit 1)
		(exclude_from_sim no)
		(in_bom yes)
		(on_board yes)
		(dnp yes)
		(fields_autoplaced yes)
		(property "Reference" "R9"
			(at 207.01 27.94 90)
			(effects
				(font
					(size 1.27 1.27)
					(thickness 0.15)
				)
				(justify right)
			)
		)
		(property "Value" "R_0R_0201"
			(at 217.17 11.43 0)
			(effects
				(font
					(size 1.27 1.27)
					(thickness 0.15)
				)
				(justify left bottom)
				(hide yes)
			)
		)
		(property "Footprint" "antmicro-footprints:R_0201"
			(at 219.71 11.43 0)
			(effects
				(font
					(size 1.27 1.27)
					(thickness 0.15)
				)
				(justify left bottom)
				(hide yes)
			)
		)
		(property "Datasheet" "https://www.bourns.com/docs/product-datasheets/cr.pdf"
			(at 222.25 11.43 0)
			(effects
				(font
					(size 1.27 1.27)
					(thickness 0.15)
				)
				(justify left bottom)
				(hide yes)
			)
		)
		(property "Description" "SMD Chip Resistor"
			(at 204.47 31.75 0)
			(effects
				(font
					(size 1.27 1.27)
				)
				(hide yes)
			)
		)
		(property "MPN" "CR0201-FX-0R00GLF"
			(at 224.79 11.43 0)
			(effects
				(font
					(size 1.27 1.27)
					(thickness 0.15)
				)
				(justify left bottom)
				(hide yes)
			)
		)
		(property "Manufacturer" "Bourns"
			(at 227.33 11.43 0)
			(effects
				(font
					(size 1.27 1.27)
					(thickness 0.15)
				)
				(justify left bottom)
				(hide yes)
			)
		)
		(property "License" "Apache-2.0"
			(at 229.87 11.43 0)
			(effects
				(font
					(size 1.27 1.27)
					(thickness 0.15)
				)
				(justify left bottom)
				(hide yes)
			)
		)
		(property "Author" "Antmicro"
			(at 232.41 11.43 0)
			(effects
				(font
					(size 1.27 1.27)
					(thickness 0.15)
				)
				(justify left bottom)
				(hide yes)
			)
		)
		(property "Val" "0R"
			(at 207.01 30.48 90)
			(effects
				(font
					(size 1.27 1.27)
					(thickness 0.15)
				)
				(justify right)
			)
		)
		(property "Tolerance" "1%"
			(at 214.63 11.43 0)
			(effects
				(font
					(size 1.27 1.27)
				)
				(justify left bottom)
				(hide yes)
			)
		)
		(pin "2"
		)
		(pin "1"
		)
		(instances
			(project "antmicro-m2-oculink-adapter-hw"
				(path ""
					(reference "R9")
					(unit 1)
				)
			)
		)
	)
	(symbol
		(lib_id "Resistors0402:R_0R_0402")
		(at 240.03 57.15 90)
		(unit 1)
		(exclude_from_sim no)
		(in_bom yes)
		(on_board yes)
		(dnp yes)
		(fields_autoplaced yes)
		(property "Reference" "R12"
			(at 242.57 53.34 90)
			(effects
				(font
					(size 1.27 1.27)
					(thickness 0.15)
				)
				(justify right)
			)
		)
		(property "Value" "R_0R_0402"
			(at 252.73 36.83 0)
			(effects
				(font
					(size 1.27 1.27)
					(thickness 0.15)
				)
				(justify left bottom)
				(hide yes)
			)
		)
		(property "Footprint" "antmicro-footprints:R_0402_1005Metric"
			(at 255.27 36.83 0)
			(effects
				(font
					(size 1.27 1.27)
					(thickness 0.15)
				)
				(justify left bottom)
				(hide yes)
			)
		)
		(property "Datasheet" "https://industrial.panasonic.com/cdbs/www-data/pdf/RDA0000/AOA0000C301.pdf"
			(at 257.81 36.83 0)
			(effects
				(font
					(size 1.27 1.27)
					(thickness 0.15)
				)
				(justify left bottom)
				(hide yes)
			)
		)
		(property "Description" "SMD Chip Resistor, Jumper, 0 ohm, 100 mW, 0402 [1005 Metric], Thick Film, General Purpose"
			(at 240.03 57.15 0)
			(effects
				(font
					(size 1.27 1.27)
				)
				(hide yes)
			)
		)
		(property "MPN" "ERJ2GE0R00X"
			(at 260.35 36.83 0)
			(effects
				(font
					(size 1.27 1.27)
					(thickness 0.15)
				)
				(justify left bottom)
				(hide yes)
			)
		)
		(property "Manufacturer" "Panasonic"
			(at 262.89 36.83 0)
			(effects
				(font
					(size 1.27 1.27)
					(thickness 0.15)
				)
				(justify left bottom)
				(hide yes)
			)
		)
		(property "License" "Apache-2.0"
			(at 265.43 36.83 0)
			(effects
				(font
					(size 1.27 1.27)
					(thickness 0.15)
				)
				(justify left bottom)
				(hide yes)
			)
		)
		(property "Author" "Antmicro"
			(at 267.97 36.83 0)
			(effects
				(font
					(size 1.27 1.27)
					(thickness 0.15)
				)
				(justify left bottom)
				(hide yes)
			)
		)
		(property "Val" "0R"
			(at 242.57 55.88 90)
			(effects
				(font
					(size 1.27 1.27)
					(thickness 0.15)
				)
				(justify right)
			)
		)
		(property "Tolerance" "~"
			(at 250.19 36.83 0)
			(effects
				(font
					(size 1.27 1.27)
				)
				(justify left bottom)
				(hide yes)
			)
		)
		(property "Current" "1A"
			(at 270.51 36.83 0)
			(effects
				(font
					(size 1.27 1.27)
					(thickness 0.15)
				)
				(justify left bottom)
				(hide yes)
			)
		)
		(pin "2"
		)
		(pin "1"
		)
		(instances
			(project "antmicro-m2-oculink-adapter-hw"
				(path ""
					(reference "R12")
					(unit 1)
				)
			)
		)
	)
	(symbol
		(lib_id "TestPoints:TP_1.5mm_SMD")
		(at 44.45 93.98 90)
		(unit 1)
		(exclude_from_sim no)
		(in_bom no)
		(on_board yes)
		(dnp no)
		(property "Reference" "TP2"
			(at 45.212 90.678 90)
			(effects
				(font
					(size 1.27 1.27)
					(thickness 0.15)
				)
				(justify right)
			)
		)
		(property "Value" "TP_1.5mm_SMD"
			(at 52.07 78.74 0)
			(effects
				(font
					(size 1.27 1.27)
					(thickness 0.15)
				)
				(justify left bottom)
				(hide yes)
			)
		)
		(property "Footprint" "antmicro-footprints:TP_SMD_1.5mm"
			(at 54.61 78.74 0)
			(effects
				(font
					(size 1.27 1.27)
					(thickness 0.15)
				)
				(justify left bottom)
				(hide yes)
			)
		)
		(property "Datasheet" ""
			(at 57.15 76.2 0)
			(effects
				(font
					(size 1.27 1.27)
					(thickness 0.15)
				)
				(justify left bottom)
				(hide yes)
			)
		)
		(property "Description" "test point, SMT"
			(at 44.45 93.98 0)
			(effects
				(font
					(size 1.27 1.27)
				)
				(hide yes)
			)
		)
		(property "MPN" ""
			(at 44.45 93.98 0)
			(effects
				(font
					(size 1.27 1.27)
				)
				(hide yes)
			)
		)
		(property "Manufacturer" ""
			(at 44.45 93.98 0)
			(effects
				(font
					(size 1.27 1.27)
				)
				(hide yes)
			)
		)
		(property "Author" "Antmicro"
			(at 59.69 78.74 0)
			(effects
				(font
					(size 1.27 1.27)
					(thickness 0.15)
				)
				(justify left bottom)
				(hide yes)
			)
		)
		(property "License" "Apache-2.0"
			(at 62.23 78.74 0)
			(effects
				(font
					(size 1.27 1.27)
					(thickness 0.15)
				)
				(justify left bottom)
				(hide yes)
			)
		)
		(pin "1"
		)
		(instances
			(project "antmicro-m2-oculink-adapter-hw"
				(path ""
					(reference "TP2")
					(unit 1)
				)
			)
		)
	)
	(symbol
		(lib_id "antmicropower:GND")
		(at 218.44 72.39 0)
		(unit 1)
		(exclude_from_sim no)
		(in_bom yes)
		(on_board yes)
		(dnp no)
		(property "Reference" "#PWR05"
			(at 227.33 74.93 0)
			(effects
				(font
					(size 1.27 1.27)
					(thickness 0.15)
				)
				(justify left bottom)
				(hide yes)
			)
		)
		(property "Value" "GND"
			(at 218.44 76.2 0)
			(effects
				(font
					(size 1.27 1.27)
					(thickness 0.15)
				)
			)
		)
		(property "Footprint" ""
			(at 227.33 80.01 0)
			(effects
				(font
					(size 1.27 1.27)
					(thickness 0.15)
				)
				(justify left bottom)
				(hide yes)
			)
		)
		(property "Datasheet" ""
			(at 227.33 85.09 0)
			(effects
				(font
					(size 1.27 1.27)
					(thickness 0.15)
				)
				(justify left bottom)
				(hide yes)
			)
		)
		(property "Description" ""
			(at 218.44 72.39 0)
			(effects
				(font
					(size 1.27 1.27)
				)
				(hide yes)
			)
		)
		(property "Author" "Antmicro"
			(at 227.33 80.01 0)
			(effects
				(font
					(size 1.27 1.27)
					(thickness 0.15)
				)
				(justify left bottom)
				(hide yes)
			)
		)
		(property "License" "Apache-2.0"
			(at 227.33 82.55 0)
			(effects
				(font
					(size 1.27 1.27)
					(thickness 0.15)
				)
				(justify left bottom)
				(hide yes)
			)
		)
		(pin "1"
		)
		(instances
			(project "antmicro-m2-oculink-adapter-hw"
				(path ""
					(reference "#PWR05")
					(unit 1)
				)
			)
		)
	)
	(symbol
		(lib_id "Resistors0402:R_0R_0402")
		(at 154.94 60.96 0)
		(unit 1)
		(exclude_from_sim no)
		(in_bom yes)
		(on_board yes)
		(dnp no)
		(fields_autoplaced yes)
		(property "Reference" "R8"
			(at 157.48 54.61 0)
			(effects
				(font
					(size 1.27 1.27)
					(thickness 0.15)
				)
			)
		)
		(property "Value" "R_0R_0402"
			(at 175.26 73.66 0)
			(effects
				(font
					(size 1.27 1.27)
					(thickness 0.15)
				)
				(justify left bottom)
				(hide yes)
			)
		)
		(property "Footprint" "antmicro-footprints:R_0402_1005Metric"
			(at 175.26 76.2 0)
			(effects
				(font
					(size 1.27 1.27)
					(thickness 0.15)
				)
				(justify left bottom)
				(hide yes)
			)
		)
		(property "Datasheet" "https://industrial.panasonic.com/cdbs/www-data/pdf/RDA0000/AOA0000C301.pdf"
			(at 175.26 78.74 0)
			(effects
				(font
					(size 1.27 1.27)
					(thickness 0.15)
				)
				(justify left bottom)
				(hide yes)
			)
		)
		(property "Description" "SMD Chip Resistor, Jumper, 0 ohm, 100 mW, 0402 [1005 Metric], Thick Film, General Purpose"
			(at 154.94 60.96 0)
			(effects
				(font
					(size 1.27 1.27)
				)
				(hide yes)
			)
		)
		(property "MPN" "ERJ2GE0R00X"
			(at 175.26 81.28 0)
			(effects
				(font
					(size 1.27 1.27)
					(thickness 0.15)
				)
				(justify left bottom)
				(hide yes)
			)
		)
		(property "Manufacturer" "Panasonic"
			(at 175.26 83.82 0)
			(effects
				(font
					(size 1.27 1.27)
					(thickness 0.15)
				)
				(justify left bottom)
				(hide yes)
			)
		)
		(property "License" "Apache-2.0"
			(at 175.26 86.36 0)
			(effects
				(font
					(size 1.27 1.27)
					(thickness 0.15)
				)
				(justify left bottom)
				(hide yes)
			)
		)
		(property "Author" "Antmicro"
			(at 175.26 88.9 0)
			(effects
				(font
					(size 1.27 1.27)
					(thickness 0.15)
				)
				(justify left bottom)
				(hide yes)
			)
		)
		(property "Val" "0R"
			(at 157.48 57.15 0)
			(effects
				(font
					(size 1.27 1.27)
					(thickness 0.15)
				)
			)
		)
		(property "Tolerance" "~"
			(at 175.26 71.12 0)
			(effects
				(font
					(size 1.27 1.27)
				)
				(justify left bottom)
				(hide yes)
			)
		)
		(property "Current" "1A"
			(at 175.26 91.44 0)
			(effects
				(font
					(size 1.27 1.27)
					(thickness 0.15)
				)
				(justify left bottom)
				(hide yes)
			)
		)
		(pin "2"
		)
		(pin "1"
		)
		(instances
			(project "antmicro-m2-oculink-adapter-hw"
				(path ""
					(reference "R8")
					(unit 1)
				)
			)
		)
	)
	(symbol
		(lib_id "PciConnectors:OCuLink_x4_Amphenol_G14A421211112HR")
		(at 246.38 59.69 0)
		(unit 1)
		(exclude_from_sim no)
		(in_bom yes)
		(on_board yes)
		(dnp no)
		(property "Reference" "J2"
			(at 259.08 52.07 0)
			(effects
				(font
					(size 1.27 1.27)
					(thickness 0.15)
				)
			)
		)
		(property "Value" "OCuLink_x4_Amphenol_G14A421211112HR"
			(at 285.75 72.39 0)
			(effects
				(font
					(size 1.27 1.27)
					(thickness 0.15)
				)
				(justify left bottom)
				(hide yes)
			)
		)
		(property "Footprint" "antmicro-footprints:Amphenol_G14A421211112HR"
			(at 285.75 74.93 0)
			(effects
				(font
					(size 1.27 1.27)
					(thickness 0.15)
				)
				(justify left bottom)
				(hide yes)
			)
		)
		(property "Datasheet" "https://cdn.amphenol-cs.com/media/wysiwyg/files/drawing/g14a421x1bxxxhr.pdf"
			(at 285.75 77.47 0)
			(effects
				(font
					(size 1.27 1.27)
					(thickness 0.15)
				)
				(justify left bottom)
				(hide yes)
			)
		)
		(property "Description" "I/O Connectors OCulink, Receptacle, 0.5mm pitch, 4X, R/A SMT with shell leg SMT type, 30U\" gold plating, LCP, black, T&R packing"
			(at 246.38 59.69 0)
			(effects
				(font
					(size 1.27 1.27)
				)
				(hide yes)
			)
		)
		(property "Manufacturer" "Amphenol"
			(at 285.75 69.85 0)
			(effects
				(font
					(size 1.27 1.27)
					(thickness 0.15)
				)
				(justify left bottom)
				(hide yes)
			)
		)
		(property "MPN" "G14A421211112HR"
			(at 259.08 54.61 0)
			(effects
				(font
					(size 1.27 1.27)
					(thickness 0.15)
				)
			)
		)
		(property "Author" "Antmicro"
			(at 285.75 80.01 0)
			(effects
				(font
					(size 1.27 1.27)
					(thickness 0.15)
				)
				(justify left bottom)
				(hide yes)
			)
		)
		(property "License" "Apache-2.0"
			(at 285.75 82.55 0)
			(effects
				(font
					(size 1.27 1.27)
					(thickness 0.15)
				)
				(justify left bottom)
				(hide yes)
			)
		)
		(pin "B15"
		)
		(pin "A11"
		)
		(pin "B12"
		)
		(pin "B9"
		)
		(pin "B20"
		)
		(pin "A5"
		)
		(pin "A1"
		)
		(pin "A17"
		)
		(pin "B11"
		)
		(pin "A9"
		)
		(pin "A2"
		)
		(pin "SH"
		)
		(pin "B10"
		)
		(pin "A4"
		)
		(pin "B6"
		)
		(pin "B2"
		)
		(pin "A10"
		)
		(pin "B5"
		)
		(pin "A12"
		)
		(pin "B1"
		)
		(pin "B13"
		)
		(pin "B14"
		)
		(pin "A21"
		)
		(pin "B8"
		)
		(pin "A16"
		)
		(pin "B7"
		)
		(pin "A14"
		)
		(pin "A19"
		)
		(pin "B17"
		)
		(pin "B21"
		)
		(pin "A3"
		)
		(pin "B18"
		)
		(pin "A20"
		)
		(pin "A15"
		)
		(pin "A8"
		)
		(pin "A18"
		)
		(pin "B4"
		)
		(pin "A7"
		)
		(pin "A6"
		)
		(pin "B19"
		)
		(pin "B16"
		)
		(pin "A13"
		)
		(pin "B3"
		)
		(instances
			(project ""
				(path ""
					(reference "J2")
					(unit 1)
				)
			)
		)
	)
	(symbol
		(lib_id "antmicroResistorsmisc:R_0R_0201")
		(at 175.26 43.18 180)
		(unit 1)
		(exclude_from_sim no)
		(in_bom yes)
		(on_board yes)
		(dnp yes)
		(fields_autoplaced yes)
		(property "Reference" "R2"
			(at 172.72 46.99 0)
			(effects
				(font
					(size 1.27 1.27)
					(thickness 0.15)
				)
			)
		)
		(property "Value" "R_0R_0201"
			(at 154.94 30.48 0)
			(effects
				(font
					(size 1.27 1.27)
					(thickness 0.15)
				)
				(justify left bottom)
				(hide yes)
			)
		)
		(property "Footprint" "antmicro-footprints:R_0201"
			(at 154.94 27.94 0)
			(effects
				(font
					(size 1.27 1.27)
					(thickness 0.15)
				)
				(justify left bottom)
				(hide yes)
			)
		)
		(property "Datasheet" "https://www.bourns.com/docs/product-datasheets/cr.pdf"
			(at 154.94 25.4 0)
			(effects
				(font
					(size 1.27 1.27)
					(thickness 0.15)
				)
				(justify left bottom)
				(hide yes)
			)
		)
		(property "Description" "SMD Chip Resistor"
			(at 175.26 43.18 0)
			(effects
				(font
					(size 1.27 1.27)
				)
				(hide yes)
			)
		)
		(property "MPN" "CR0201-FX-0R00GLF"
			(at 154.94 22.86 0)
			(effects
				(font
					(size 1.27 1.27)
					(thickness 0.15)
				)
				(justify left bottom)
				(hide yes)
			)
		)
		(property "Manufacturer" "Bourns"
			(at 154.94 20.32 0)
			(effects
				(font
					(size 1.27 1.27)
					(thickness 0.15)
				)
				(justify left bottom)
				(hide yes)
			)
		)
		(property "License" "Apache-2.0"
			(at 154.94 17.78 0)
			(effects
				(font
					(size 1.27 1.27)
					(thickness 0.15)
				)
				(justify left bottom)
				(hide yes)
			)
		)
		(property "Author" "Antmicro"
			(at 154.94 15.24 0)
			(effects
				(font
					(size 1.27 1.27)
					(thickness 0.15)
				)
				(justify left bottom)
				(hide yes)
			)
		)
		(property "Val" "0R"
			(at 172.72 49.53 0)
			(effects
				(font
					(size 1.27 1.27)
					(thickness 0.15)
				)
			)
		)
		(property "Tolerance" "1%"
			(at 154.94 33.02 0)
			(effects
				(font
					(size 1.27 1.27)
				)
				(justify left bottom)
				(hide yes)
			)
		)
		(pin "1"
		)
		(pin "2"
		)
		(instances
			(project "antmicro-m2-oculink-adapter-hw"
				(path ""
					(reference "R2")
					(unit 1)
				)
			)
		)
	)
	(symbol
		(lib_id "TestPoints:TP_1.5mm_SMD")
		(at 36.83 93.98 90)
		(unit 1)
		(exclude_from_sim no)
		(in_bom no)
		(on_board yes)
		(dnp no)
		(property "Reference" "TP1"
			(at 37.846 90.678 90)
			(effects
				(font
					(size 1.27 1.27)
					(thickness 0.15)
				)
				(justify right)
			)
		)
		(property "Value" "TP_1.5mm_SMD"
			(at 44.45 78.74 0)
			(effects
				(font
					(size 1.27 1.27)
					(thickness 0.15)
				)
				(justify left bottom)
				(hide yes)
			)
		)
		(property "Footprint" "antmicro-footprints:TP_SMD_1.5mm"
			(at 46.99 78.74 0)
			(effects
				(font
					(size 1.27 1.27)
					(thickness 0.15)
				)
				(justify left bottom)
				(hide yes)
			)
		)
		(property "Datasheet" ""
			(at 49.53 76.2 0)
			(effects
				(font
					(size 1.27 1.27)
					(thickness 0.15)
				)
				(justify left bottom)
				(hide yes)
			)
		)
		(property "Description" "test point, SMT"
			(at 36.83 93.98 0)
			(effects
				(font
					(size 1.27 1.27)
				)
				(hide yes)
			)
		)
		(property "MPN" ""
			(at 36.83 93.98 0)
			(effects
				(font
					(size 1.27 1.27)
				)
				(hide yes)
			)
		)
		(property "Manufacturer" ""
			(at 36.83 93.98 0)
			(effects
				(font
					(size 1.27 1.27)
				)
				(hide yes)
			)
		)
		(property "Author" "Antmicro"
			(at 52.07 78.74 0)
			(effects
				(font
					(size 1.27 1.27)
					(thickness 0.15)
				)
				(justify left bottom)
				(hide yes)
			)
		)
		(property "License" "Apache-2.0"
			(at 54.61 78.74 0)
			(effects
				(font
					(size 1.27 1.27)
					(thickness 0.15)
				)
				(justify left bottom)
				(hide yes)
			)
		)
		(pin "1"
		)
		(instances
			(project ""
				(path ""
					(reference "TP1")
					(unit 1)
				)
			)
		)
	)
	(sheet_instances
		(path "/"
			(page "1")
		)
	)
)
